G04 ================== begin FILE IDENTIFICATION RECORD ==================*
G04 Layout Name:  F:/<user>/2022/FB/R4006-TIMING/brd/gerber-3/R4006-B0001-02_R01.brd*
G04 Film Name:    R4006-B0001-02_R01_L05*
G04 File Format:  Gerber RS274X*
G04 File Origin:  Cadence Allegro 17.2-S079*
G04 Origin Date:  Fri Feb 25 18:14:43 2022*
G04 *
G04 Layer:  ETCH/L05_VCC1*
G04 Layer:  PIN/L05_VCC1*
G04 Layer:  VIA CLASS/L05_VCC1*
G04 Layer:  MANUFACTURING/L05_VCC1*
G04 Layer:  MANUFACTURING/CELESTICA_LEGEND*
G04 *
G04 Offset:    (0.00 0.00)*
G04 Mirror:    No*
G04 Mode:      Negative*
G04 Rotation:  0*
G04 FullContactRelief:  No*
G04 UndefLineWidth:     6.00*
G04 ================== end FILE IDENTIFICATION RECORD ====================*
%FSLAX55Y55*MOIN*%
%IR0*IPPOS*OFA0.00000B0.00000*MIA0B0*SFA1.00000B1.00000*%
%ADD12C,.02*%
%ADD10C,.03*%
%ADD13C,.032*%
%ADD15C,.033*%
%ADD19C,.026*%
%ADD21C,.018*%
%ADD20C,.028*%
%ADD16C,.082*%
%ADD29C,.056*%
%ADD18C,.039*%
%ADD11C,.086*%
%ADD25C,.099*%
%ADD22C,.102*%
%ADD14C,.15*%
%ADD27C,.143*%
%ADD23C,.125*%
%ADD28O,.074X.047*%
%ADD17O,.086X.047*%
%ADD24C,.189*%
%AMMACRO26*
4,1,18,.0371,.0272,
.04126,.020344,
.044166,.012871,
.04573,.005006,
.045904,-.003011,
.044684,-.010936,
.042106,-.01853,
.038249,-.02556,
.0371,-.0272,
.04067,-.03077,
.045395,-.02324,
.048741,-.015004,
.050606,-.006313,
.050934,.002571,
.049713,.011376,
.046983,.019836,
.042824,.027693,
.04067,.03077,
.0371,.0272,
270.*
4,1,18,.0272,-.0371,
.020344,-.04126,
.012871,-.044166,
.005006,-.04573,
-.003011,-.045904,
-.010936,-.044684,
-.01853,-.042106,
-.02556,-.038249,
-.0272,-.0371,
-.03077,-.04067,
-.02324,-.045395,
-.015004,-.048741,
-.006313,-.050606,
.002571,-.050934,
.011376,-.049713,
.019836,-.046983,
.027693,-.042824,
.03077,-.04067,
.0272,-.0371,
270.*
4,1,18,-.0371,-.0272,
-.04126,-.020344,
-.044166,-.012871,
-.04573,-.005006,
-.045904,.003011,
-.044684,.010936,
-.042106,.01853,
-.038249,.02556,
-.0371,.0272,
-.04067,.03077,
-.045395,.02324,
-.048741,.015004,
-.050606,.006313,
-.050934,-.002571,
-.049713,-.011376,
-.046983,-.019836,
-.042824,-.027693,
-.04067,-.03077,
-.0371,-.0272,
270.*
4,1,18,-.0272,.0371,
-.020344,.04126,
-.012871,.044166,
-.005006,.04573,
.003011,.045904,
.010936,.044684,
.01853,.042106,
.02556,.038249,
.0272,.0371,
.03077,.04067,
.02324,.045395,
.015004,.048741,
.006313,.050606,
-.002571,.050934,
-.011376,.049713,
-.019836,.046983,
-.027693,.042824,
-.03077,.04067,
-.0272,.0371,
270.*
%
%ADD26MACRO26*%
%ADD30C,.01*%
%ADD31C,.005*%
%ADD32C,.006*%
%ADD42R,.07002X.03002*%
%ADD38R,.07002X.03004*%
%ADD43R,.07004X.03004*%
%ADD39R,.03004X.07004*%
%ADD35C,.14006*%
%ADD44R,.02802X.06002*%
%ADD33C,.12406*%
%ADD41R,.02802X.06004*%
%ADD36R,.06004X.02804*%
%ADD40C,.28406*%
%ADD46C,.16806*%
%ADD45O,.02606X.06543*%
%ADD34C,.27606*%
%ADD37R,.09004X.05804*%
G75*
%LPD*%
G75*
G36*
G01X-10000Y-10000D02*
X670039D01*
Y447598D01*
X-10000D01*
Y-10000D01*
G37*
%LPC*%
G75*
G36*
G01X88001Y190171D02*
X87921Y190037D01*
G03X87498Y188501I2579J-1537D01*
G01Y188500D01*
G03X90500Y185498I3002J0D01*
G01X90501D01*
G03X92037Y185921I-1J3002D01*
G01X92171Y186001D01*
X166000Y112172D01*
Y57666D01*
G03X154795Y43012I3980J-14654D01*
G01Y25717D01*
X139299D01*
Y46260D01*
G03X127362Y58197I-11937J0D01*
G01X122464D01*
X122429Y58353D01*
G03X116571I-2929J-659D01*
G01X116536Y58197D01*
X62992D01*
G03X51055Y46260I0J-11937D01*
G01Y25717D01*
X38874D01*
G02X38611Y26418I0J400D01*
G03X43330Y36809I-9083J10392D01*
G01Y36811D01*
G03X15726I-13802J0D01*
G01Y36809D01*
G03X20445Y26418I13802J1D01*
G02X20182Y25717I-263J-301D01*
G01X8000D01*
Y55061D01*
G03X12541Y61260I-1961J6199D01*
G03X8000Y67459I-6502J0D01*
G01Y75061D01*
G03Y87459I-1961J6199D01*
G01Y112147D01*
G03Y124545I-1961J6199D01*
G01Y132147D01*
G03Y144545I-1961J6199D01*
G01Y169234D01*
G03Y181632I-1961J6199D01*
G01Y189234D01*
G03Y201632I-1961J6199D01*
G01Y226321D01*
G03Y238719I-1961J6199D01*
G01Y246321D01*
G03Y258719I-1961J6199D01*
G01Y429598D01*
X49949D01*
X52500Y427047D01*
Y387500D01*
G03X53086Y386086I1999J0D01*
G01X56000Y383172D01*
Y291600D01*
G03Y286400I1499J-2600D01*
G01Y229100D01*
G03Y223900I1499J-2600D01*
G01Y223000D01*
G03X56586Y221586I1999J0D01*
G01X88001Y190171D01*
G37*
G36*
G01X93034Y243475D02*
G03X94695Y243977I-1J3002D01*
G01X223000Y115672D01*
Y61214D01*
X222844Y61179D01*
G03Y55321I655J-2929D01*
G01X223000Y55286D01*
Y40899D01*
G03X213260Y29331I2000J-11568D01*
G01Y26200D01*
X185165D01*
Y43012D01*
G03X170000Y58197I-15185J0D01*
G01Y113000D01*
G03X169414Y114414I-1999J0D01*
G01X60000Y223828D01*
Y224838D01*
X60031Y224887D01*
G03X60502Y226500I-2530J1614D01*
G03X60000Y228162I-3002J0D01*
G01Y287338D01*
G03Y290662I-2500J1662D01*
G01Y383172D01*
X61328Y384500D01*
X73672D01*
X76000Y382172D01*
Y363000D01*
G03X76586Y361586I1999J0D01*
G01X88500Y349672D01*
Y251000D01*
G03X89086Y249586I1999J0D01*
G01X90529Y248143D01*
X90450Y248009D01*
G03X90030Y246478I2582J-1531D01*
G01Y246477D01*
G03X93032Y243475I3002J0D01*
G01X93034D01*
G37*
G36*
G01X135712Y415540D02*
X135610Y415558D01*
G03X135100Y415602I-512J-2958D01*
G03X132098Y412600I0J-3002D01*
G03X132451Y411188I3002J0D01*
G01X132475Y411144D01*
X132500Y411098D01*
Y409714D01*
X132481Y409673D01*
G03X132198Y408401I2719J-1272D01*
G01Y408400D01*
G03X132500Y407088I3001J0D01*
G01Y396097D01*
G03X132498Y396000I3000J-110D01*
G03X132500Y395903I3002J13D01*
G01Y390597D01*
G03X132498Y390500I3000J-110D01*
G03X132500Y390403I3002J13D01*
G01Y383097D01*
G03X132498Y383000I3000J-110D01*
G03X132500Y382903I3002J13D01*
G01Y366828D01*
X124172Y358500D01*
X96500D01*
G03X95086Y357914I0J-1999D01*
G01X92172Y355000D01*
X89000D01*
G03X88921Y354998I11J-2000D01*
G01X88833Y354995D01*
X85784Y358044D01*
X85890Y358183D01*
G03X86502Y360000I-2391J1817D01*
G03X83500Y363002I-3002J0D01*
G03X81683Y362389I1J-3002D01*
G01X81544Y362284D01*
X80000Y363828D01*
Y383000D01*
G03X79414Y384414I-1999J0D01*
G01X75914Y387914D01*
G03X74500Y388500I-1414J-1413D01*
G01X60500D01*
G03X59086Y387914I0J-1999D01*
G01X58000Y386828D01*
X56500Y388328D01*
Y427297D01*
X58801Y429598D01*
X601949D01*
X604000Y427547D01*
Y391000D01*
G03X604586Y389586I1999J0D01*
G01X611500Y382672D01*
Y328328D01*
X604172Y321000D01*
X589828D01*
X584510Y326318D01*
G02X584974Y326957I283J282D01*
G03X588779Y326046I3805J7491D01*
G03X597182Y334449I0J8403D01*
G01Y367682D01*
X597175Y367844D01*
G03X588670Y375921I-8396J-325D01*
G01Y399880D01*
G03X588084Y401294I-1999J0D01*
G01X580464Y408914D01*
G03X579050Y409500I-1414J-1413D01*
G01X541024D01*
G03X535976I-2524J-1625D01*
G01X530097D01*
G03X530000Y409502I-110J-3000D01*
G03X529903Y409500I13J-3002D01*
G01X513328D01*
X508017Y414811D01*
G03X494094Y426210I-13923J-2803D01*
G01X494093D01*
G03X487337Y424500I0J-14202D01*
G01X425200D01*
X425164Y424655D01*
G03X422337Y426902I-2827J-655D01*
G03X419904Y425582I0J-2902D01*
G02X419233I-335J218D01*
G03X416800Y426902I-2433J-1582D01*
G03X413973Y424655I0J-2902D01*
G01X413937Y424500D01*
X365574D01*
G03X360626I-2474J-1699D01*
G01X339006D01*
G03X333594I-2706J-1300D01*
G01X324167D01*
X324119Y424631D01*
G03X318481I-2819J-1030D01*
G01X318433Y424500D01*
X262663D01*
G03X255907Y426210I-6756J-12492D01*
G01X255905D01*
G03X249149Y424500I0J-14202D01*
G01X145500D01*
G03X144086Y423914I0J-1999D01*
G01X135712Y415540D01*
G37*
G36*
G01X236882Y326190D02*
X248396D01*
X251006Y323580D01*
G02X250865Y322924I-283J-282D01*
G03X241704Y309646I5042J-13278D01*
G03X255906Y295444I14202J0D01*
G03X269184Y304605I0J14203D01*
G02X269840Y304746I374J-142D01*
G01X286793Y287793D01*
G03X287500Y287500I707J706D01*
G01X322998D01*
Y265964D01*
X322842Y265929D01*
G03Y260071I658J-2929D01*
G01X322998Y260036D01*
Y257294D01*
G03Y252106I1303J-2594D01*
G01Y238724D01*
G03Y233276I1003J-2724D01*
G01Y230330D01*
G03Y224670I1002J-2830D01*
G01Y223043D01*
G03Y218457I1003J-2293D01*
G01Y191700D01*
X321308D01*
Y188898D01*
X322998D01*
Y129085D01*
X329085Y122999D01*
X284086Y78000D01*
X228789D01*
X227000Y79789D01*
Y116500D01*
G03X226414Y117914I-1999J0D01*
G01X92500Y251828D01*
Y283780D01*
X188440D01*
G03X189147Y284073I0J999D01*
G01X231264Y326190D01*
X234018D01*
X234050Y326179D01*
G03X234375Y326125I324J946D01*
G03X234700Y326179I1J1000D01*
G01X234732Y326190D01*
X235868D01*
X235892Y326184D01*
G03X236375Y326125I482J1941D01*
G03X236858Y326184I1J2000D01*
G01X236882Y326190D01*
G37*
G36*
G01X151483Y333467D02*
G03X151190Y332760I706J-707D01*
G01Y317870D01*
G03X151483Y317163I999J0D01*
G01X153183Y315463D01*
G03X154963Y313683I2817J1037D01*
G01X156253Y312393D01*
G03X156960Y312100I707J706D01*
G01X170480D01*
G03X171187Y312393I0J999D01*
G01X199004Y340210D01*
X225026D01*
X229850Y335386D01*
Y331507D01*
G03Y330243I775J-632D01*
G01Y327607D01*
X188025Y285782D01*
X92500D01*
Y349672D01*
X97328Y354500D01*
X125000D01*
G03X126414Y355086I0J1999D01*
G01X135328Y364000D01*
X171461D01*
X173130Y362331D01*
Y342594D01*
X166066Y335530D01*
X153960D01*
G03X153253Y335237I0J-999D01*
G01X151483Y333467D01*
G37*
G36*
G01X365029Y420500D02*
X481939D01*
G02X482272Y419878I0J-400D01*
G03X479892Y412008I11822J-7870D01*
G03X494094Y397806I14202J0D01*
G03X507849Y408470I0J14203D01*
G02X508519Y408653I387J-100D01*
G01X511086Y406086D01*
G03X512500Y405500I1414J1413D01*
G01X527169D01*
G03X532831I2831J1001D01*
G01X536664D01*
G03X540336I1836J2375D01*
G01X578222D01*
X584670Y399052D01*
Y376498D01*
X578586Y370414D01*
G03X578000Y369000I1413J-1414D01*
G01Y368847D01*
X577944Y368789D01*
G03Y364611I2156J-2089D01*
G01X578000Y364553D01*
Y363744D01*
X577950Y363687D01*
G03Y359713I2249J-1987D01*
G01X578000Y359656D01*
Y358631D01*
X577956Y358576D01*
G03X577298Y356700I2345J-1876D01*
G03X578000Y354771I3001J0D01*
G01Y328000D01*
G03X578586Y326586I1999J0D01*
G01X586422Y318750D01*
X577586Y309914D01*
G03X577000Y308500I1413J-1414D01*
G01Y238924D01*
G03X575898Y236600I1900J-2324D01*
G03X576080Y235571I3002J0D01*
G01X576123Y235451D01*
X570172Y229500D01*
X568803D01*
G03X564597I-2103J-2001D01*
G01X561984D01*
G03X557016I-2484J-1500D01*
G01X555593D01*
G03X553122Y230881I-2471J-1520D01*
G03X550961Y229916I0J-2902D01*
G02X550360Y229923I-297J267D01*
G03X548158Y230935I-2202J-1890D01*
G03X545654Y229500I0J-2902D01*
G01X534328D01*
X531500Y232328D01*
Y254707D01*
G03Y260253I-1150J2773D01*
G01Y282536D01*
X531656Y282571D01*
G03Y288429I-655J2929D01*
G01X531500Y288464D01*
Y368000D01*
G03X530914Y369414I-1999J0D01*
G01X530517Y369811D01*
X530504Y369836D01*
G03X529711Y370629I-1754J-961D01*
G01X529686Y370642D01*
X521414Y378914D01*
G03X520000Y379500I-1414J-1413D01*
G01X228831D01*
G03X226000Y381502I-2831J-1001D01*
G03X223891Y380636I0J-3001D01*
G02X223609I-141J142D01*
G03X221500Y381502I-2109J-2135D01*
G03X218669Y379500I0J-3003D01*
G01X191000D01*
G03X189586Y378914I0J-1999D01*
G01X178672Y368000D01*
X136500D01*
Y380169D01*
G03Y385831I-1001J2831D01*
G01Y387669D01*
G03X138502Y390500I-1001J2831D01*
G03X137267Y392927I-3002J0D01*
G02Y393573I236J323D01*
G03X138502Y396000I-1767J2427D01*
G03X136500Y398831I-3003J0D01*
G01Y405694D01*
G03X138202Y408400I-1300J2706D01*
G03X137294Y410551I-3002J0D01*
G03X138074Y412188I-2194J2050D01*
G01X138083Y412255D01*
X141548Y415720D01*
G03X143500Y414998I1953J2280D01*
G03X146502Y418000I0J3002D01*
G03X145890Y419817I-3003J0D01*
G01X145784Y419956D01*
X146328Y420500D01*
X243751D01*
G02X244084Y419878I0J-400D01*
G03X241704Y412008I11822J-7870D01*
G03X270108I14202J0D01*
G03X267728Y419878I-14202J0D01*
G02X268061Y420500I333J222D01*
G01X334988D01*
G03X337612I1312J2699D01*
G01X361171D01*
G03X365029I1929J2299D01*
G37*
G36*
G01X472709Y366002D02*
G03X471400Y366302I-1308J-2702D01*
G03X470091Y366002I-1J-3002D01*
G01X441100D01*
G03X435900I-2600J-1503D01*
G01X423500D01*
G03X417500I-3000J-2D01*
G01X389330D01*
G03X386500Y368002I-2830J-1002D01*
G03X384073Y366767I0J-3002D01*
G02X383427I-323J236D01*
G03X381000Y368002I-2427J-1767D01*
G03X378170Y366002I0J-3002D01*
G01X291585D01*
X283498Y357915D01*
Y343585D01*
X326498Y300585D01*
Y292415D01*
X323585Y289502D01*
X287915D01*
X269942Y307475D01*
X269957Y307574D01*
G03X270108Y309646I-14140J2072D01*
G03X255906Y323848I-14202J0D01*
G03X253834Y323697I0J-14291D01*
G01X253735Y323682D01*
X249225Y328192D01*
X238382D01*
X238364Y328338D01*
G03X237789Y329539I-1989J-214D01*
G01X237767Y329561D01*
X237754Y329586D01*
G03X237414Y330039I-1753J-962D01*
G01X235580Y331873D01*
G03X235533Y331920I-730J-683D01*
G01X233414Y334039D01*
G03X232047Y334624I-1413J-1413D01*
G01X231852Y334824D01*
Y336215D01*
X225855Y342212D01*
X198175D01*
X170065Y314102D01*
X157375D01*
X153192Y318285D01*
Y322148D01*
G03X154002Y324200I-2192J2051D01*
G03X153192Y326252I-3002J1D01*
G01Y332345D01*
X154375Y333528D01*
X166895D01*
X175132Y341765D01*
Y361842D01*
X177289Y364000D01*
X179500D01*
G03X180914Y364586I0J1999D01*
G01X191828Y375500D01*
X221394D01*
G03X221500Y375498I110J3000D01*
G03X221606Y375500I-4J3002D01*
G01X225894D01*
G03X226000Y375498I110J3000D01*
G03X226106Y375500I-4J3002D01*
G01X328536D01*
X328571Y375344D01*
G03X334429I2929J655D01*
G01X334464Y375500D01*
X335536D01*
X335571Y375344D01*
G03X338500Y372998I2929J655D01*
G03X340250Y373561I0J3001D01*
G03X342000Y372998I1750J2438D01*
G03X344929Y375344I0J3001D01*
G01X344964Y375500D01*
X376508D01*
X376535Y375331D01*
G03X382465I2965J469D01*
G01X382492Y375500D01*
X501536D01*
X501571Y375344D01*
G03X507429I2929J655D01*
G01X507464Y375500D01*
X519172D01*
X525859Y368812D01*
X523586Y366539D01*
G03X523203Y366002I1414J-1414D01*
G01X472709D01*
G37*
G36*
G01X527500Y359797D02*
Y321900D01*
G03Y315900I100J-3000D01*
G01Y301724D01*
G03Y296276I1000J-2724D01*
G01Y258424D01*
X527491Y258394D01*
G03X527348Y257480I2859J-915D01*
G03X527491Y256566I3002J1D01*
G01X527500Y256536D01*
Y231500D01*
G03X528086Y230086I1999J0D01*
G01X532086Y226086D01*
G03X533500Y225500I1414J1413D01*
G01X546742D01*
G03X549574I1416J2532D01*
G01X551613D01*
G03X554631I1509J2480D01*
G01X558026D01*
G03X560974I1474J2501D01*
G01X564597D01*
G03X568803I2103J2001D01*
G01X571002D01*
G03X571414Y225543I-1J2000D01*
G01X571520Y225566D01*
X580380Y216706D01*
G03X578998Y209400I18621J-7306D01*
G01Y209399D01*
G03X583000Y197396I20002J0D01*
G01Y80376D01*
X582994Y80352D01*
G03X582898Y79600I2906J-753D01*
G03X582994Y78848I3002J1D01*
G01X583000Y78824D01*
Y58197D01*
X316142D01*
G03X304205Y46260I0J-11937D01*
G01Y26200D01*
X236740D01*
Y29331D01*
G03X227000Y40899I-11740J0D01*
G01Y72281D01*
G02X227529Y72659I400J0D01*
G03X228498Y72498I970J2841D01*
G01X228500D01*
G03X231502Y75500I0J3002D01*
G03X231501Y75587I-3002J9D01*
G02X231900Y75998I400J11D01*
G01X239234D01*
X239281Y75865D01*
G03X239402Y75613I1227J434D01*
G02X239063Y75002I-339J-211D01*
G01X239006D01*
Y67998D01*
X242010D01*
Y75002D01*
X241953D01*
G02X241614Y75613I0J400D01*
G03X241735Y75865I-1106J686D01*
G01X241782Y75998D01*
X242548D01*
X242595Y75865D01*
G03X245049I1227J435D01*
G01X245096Y75998D01*
X245620D01*
Y74898D01*
X251624D01*
Y75998D01*
X252148D01*
X252195Y75865D01*
G03X254649I1227J435D01*
G01X254696Y75998D01*
X262233D01*
X262280Y75865D01*
G03X264734I1227J435D01*
G01X264781Y75998D01*
X265306D01*
Y74898D01*
X271308D01*
Y75998D01*
X271833D01*
X271880Y75865D01*
G03X274334I1227J435D01*
G01X274381Y75998D01*
X277381D01*
X277428Y75865D01*
G03X279882I1227J435D01*
G01X279929Y75998D01*
X280454D01*
Y74898D01*
X286456D01*
Y77540D01*
X330915Y121998D01*
X336345D01*
G03X336612Y121648I1154J603D01*
G01X336676Y121502D01*
G02X336476Y121302I-200J0D01*
G01X335998D01*
Y114298D01*
X339002D01*
Y121302D01*
X338524D01*
G02X338324Y121502I0J200D01*
G01X338388Y121648D01*
G03X338655Y121998I-887J953D01*
G01X357585D01*
X362085Y117498D01*
X399748D01*
Y114598D01*
X406752D01*
Y117498D01*
X435750D01*
Y115098D01*
X442752D01*
Y117498D01*
X547415D01*
X552502Y122585D01*
Y170915D01*
X543415Y180002D01*
X518585D01*
X513585Y175002D01*
X500000D01*
G03X494000I-3000J-2D01*
G01X488040D01*
X488025Y175185D01*
G03X485033Y177936I-2992J-252D01*
G03X482711Y176837I0J-3002D01*
G02X482002Y177090I-309J253D01*
G01Y180701D01*
X482114Y180756D01*
G03Y183276I-613J1260D01*
G01X482002Y183331D01*
Y190036D01*
X482158Y190071D01*
G03Y195929I-658J2929D01*
G01X482002Y195964D01*
Y201323D01*
G03Y206253I-1715J2465D01*
G01Y209498D01*
G03Y215502I-2J3002D01*
G01Y261915D01*
X472415Y271502D01*
X471100D01*
G03X465900I-2600J-1503D01*
G01X436415D01*
X431002Y276915D01*
Y294915D01*
X426415Y299502D01*
X397585D01*
X385000Y286917D01*
X378915Y293002D01*
X377123D01*
G03X374800Y294102I-2323J-1903D01*
G03X372691Y293236I0J-3001D01*
G02X372409I-141J142D01*
G03X368191I-2109J-2135D01*
G02X367909I-141J142D01*
G03X365800Y294102I-2109J-2135D01*
G03X363886Y293413I0J-3003D01*
G03X362100Y294002I-1786J-2413D01*
G03X359863Y293002I0J-3002D01*
G01X333100D01*
G03X330500Y294502I-2600J-1503D01*
G03X329088Y294149I0J-3002D01*
G02X328500Y294502I-188J353D01*
G01Y301000D01*
G03X328207Y301707I-999J0D01*
G01X285500Y344414D01*
Y357086D01*
X292414Y364000D01*
X378169D01*
G03X381000Y361998I2831J1001D01*
G03X383427Y363233I0J3002D01*
G02X384073I323J-236D01*
G03X386500Y361998I2427J1767D01*
G03X389331Y364000I0J3003D01*
G01X418261D01*
G03X422739I2239J2001D01*
G01X431838D01*
G03X433500Y363498I1662J2500D01*
G03X435114Y363969I0J3001D01*
G01X435163Y364000D01*
X435536D01*
X435571Y363844D01*
G03X441429I2929J655D01*
G01X441464Y364000D01*
X523346D01*
G03X523586Y363711I1652J1128D01*
G01X527500Y359797D01*
G37*
G36*
G01X367909Y288964D02*
G02X368191I141J-142D01*
G03X372409I2109J2135D01*
G02X372691I141J-142D01*
G03X374800Y288098I2109J2135D01*
G03X377669Y290216I0J3002D01*
G03X378000Y290198I328J2984D01*
G03X378677Y290275I1J3002D01*
G01X378786Y290300D01*
X384000Y285086D01*
Y273914D01*
X376293Y266207D01*
G03X376000Y265500I706J-707D01*
G01Y229100D01*
G03X374498Y226500I1499J-2600D01*
G03X374900Y225000I3002J1D01*
G03X374498Y223500I2600J-1501D01*
G03X374771Y222250I3002J1D01*
G03X374498Y221000I2729J-1251D01*
G03X374771Y219750I3002J1D01*
G03X374498Y218500I2729J-1251D01*
G03X376000Y215900I3001J0D01*
G01Y174002D01*
X370085D01*
X368304Y172220D01*
X368198Y172242D01*
G03X367602Y172302I-597J-2942D01*
G01X367600D01*
G03X366243Y171977I1J-3002D01*
G03X364700Y172404I-1544J-2577D01*
G03Y166396I0J-3004D01*
G03X364792Y166397I13J3004D01*
G02X364998Y166198I6J-200D01*
G01Y160002D01*
X350085D01*
X345498Y155415D01*
Y145585D01*
X348085Y142998D01*
X355585D01*
X356998Y141585D01*
Y124000D01*
X330914D01*
X325000Y129914D01*
Y188898D01*
X327312D01*
Y191700D01*
X325000D01*
Y217919D01*
G03Y223581I-1001J2831D01*
G01Y224669D01*
G03Y230331I-1001J2831D01*
G01Y233276D01*
G03Y238724I-1000J2724D01*
G01Y251880D01*
X325142Y251923D01*
G03Y257477I-842J2777D01*
G01X325000Y257520D01*
Y260400D01*
G03Y265600I-1499J2600D01*
G01Y288086D01*
X327175Y290261D01*
G02X327815Y290157I282J-283D01*
G03X330500Y288498I2685J1343D01*
G03X333429Y290844I0J3001D01*
G01X333464Y291000D01*
X362794D01*
X362811Y290819D01*
G03X365800Y288098I2989J281D01*
G03X367909Y288964I0J3001D01*
G37*
G36*
G01X519414Y178000D02*
X542586D01*
X550500Y170086D01*
Y123414D01*
X546586Y119500D01*
X464162D01*
G03X460838I-1662J-2500D01*
G01X431106D01*
G03X431000Y119502I-110J-3000D01*
G03X430894Y119500I4J-3002D01*
G01X420162D01*
G03X416838I-1662J-2500D01*
G01X362914D01*
X359000Y123414D01*
Y130394D01*
G03X359002Y130500I-3000J110D01*
G03X359000Y130606I-3002J-4D01*
G01Y142000D01*
G03X358707Y142707I-999J0D01*
G01X356707Y144707D01*
G03X356000Y145000I-707J-706D01*
G01X348914D01*
X347500Y146414D01*
Y154586D01*
X350914Y158000D01*
X365000D01*
Y155004D01*
X364994Y154980D01*
G03X364898Y154228I2906J-753D01*
G03X364994Y153476I3002J1D01*
G01X365000Y153452D01*
Y152500D01*
G03X365293Y151793I999J0D01*
G01X369793Y147293D01*
G03X370500Y147000I707J706D01*
G01X393753D01*
X393770Y146819D01*
G03X395067Y145640I1297J124D01*
G01X399004D01*
G03X400301Y146819I0J1303D01*
G01X400318Y147000D01*
X408500D01*
G03X409207Y147293I0J999D01*
G01X412499Y150585D01*
X418585Y144498D01*
X444943D01*
G02X445250Y143842I0J-400D01*
G03X444946Y143005I998J-836D01*
G03X446248Y141702I1303J0D01*
G01X450185D01*
G03X451488Y143005I0J1303D01*
G03X451183Y143842I-1303J-1D01*
G02X451490Y144498I307J256D01*
G01X516415D01*
X519002Y147085D01*
Y170415D01*
X515415Y174001D01*
X519414Y178000D01*
G37*
G36*
G01X400355Y172000D02*
X408086D01*
X409512Y170574D01*
X409516Y170497D01*
G03X410749Y169264I1300J67D01*
G01X410826Y169260D01*
X411500Y168586D01*
Y152414D01*
X411211Y152125D01*
X411103Y152149D01*
G03X410816Y152181I-287J-1271D01*
G03X409514Y150879I0J-1302D01*
G03X409546Y150592I1303J0D01*
G01X409570Y150484D01*
X408086Y149000D01*
X370914D01*
X367000Y152914D01*
Y165904D01*
G02X367423Y166303I400J0D01*
G03X367600Y166298I173J2997D01*
G03X370602Y169300I0J3002D01*
G03X370101Y170960I-3001J0D01*
G01X370011Y171097D01*
X370914Y172000D01*
X393716D01*
G02X394033Y171357I0J-400D01*
G03X393764Y170564I1034J-793D01*
G03X395067Y169262I1302J0D01*
G01X399004D01*
G03X400306Y170564I0J1302D01*
G03X400038Y171357I-1303J2D01*
G02X400355Y172000I317J243D01*
G37*
G36*
G01X435293Y269793D02*
G03X436000Y269500I707J706D01*
G01X465536D01*
X465571Y269344D01*
G03X468500Y266998I2929J655D01*
G03X471318Y268965I0J3002D01*
G02X471976Y269110I375J-138D01*
G01X480000Y261086D01*
Y214739D01*
G03Y210261I2001J-2239D01*
G01Y206781D01*
X479830Y206755D01*
G03Y200821I458J-2967D01*
G01X480000Y200795D01*
Y195600D01*
G03Y190400I1499J-2600D01*
G01Y175000D01*
X417500D01*
G03X416793Y174707I0J-999D01*
G01X412500Y170414D01*
X412094Y170820D01*
X412080Y170874D01*
G03X411126Y171828I-1264J-310D01*
G01X411072Y171842D01*
X409207Y173707D01*
G03X408500Y174000I-707J-706D01*
G01X378002D01*
Y215536D01*
X378158Y215571D01*
G03X380502Y218500I-658J2929D01*
G03X380229Y219750I-3002J-1D01*
G03X380502Y221000I-2729J1251D01*
G03X380229Y222250I-3002J-1D01*
G03X380502Y223500I-2729J1251D01*
G03X380100Y225000I-3002J-1D01*
G03X380502Y226500I-2600J1501D01*
G03X378158Y229429I-3002J0D01*
G01X378002Y229464D01*
Y254011D01*
G03X378302Y255200I-2202J1188D01*
G03X378002Y256389I-2502J1D01*
G01Y265085D01*
X386002Y273085D01*
Y285088D01*
X398414Y297500D01*
X407394D01*
G03X407500Y297498I110J3000D01*
G03X407606Y297500I-4J3002D01*
G01X412894D01*
G03X413000Y297498I110J3000D01*
G03X413106Y297500I-4J3002D01*
G01X425586D01*
X429000Y294086D01*
Y276500D01*
G03X429293Y275793I999J0D01*
G01X435293Y269793D01*
G37*
G36*
G01X499239Y173000D02*
X513586D01*
X517000Y169586D01*
Y147914D01*
X515586Y146500D01*
X514596D01*
G03X514500Y146502I-100J-2500D01*
G03X514404Y146500I4J-2502D01*
G01X475509D01*
G02X475109Y146910I0J400D01*
G03X475110Y146942I-1301J57D01*
G03X473807Y148244I-1302J0D01*
G01X469870D01*
G03X468568Y146942I0J-1302D01*
G01Y146910D01*
G02X468168Y146500I-400J-10D01*
G01X420391D01*
G02X419992Y146910I1J400D01*
G01Y146942D01*
G03X418690Y148244I-1302J0D01*
G03X418047Y148074I0J-1301D01*
G01X417915Y147999D01*
X415810Y150104D01*
X415885Y150236D01*
G03X416055Y150879I-1131J643D01*
G03X414753Y152181I-1302J0D01*
G03X414110Y152011I0J-1301D01*
G01X413978Y151936D01*
X413500Y152414D01*
Y168586D01*
X414265Y169351D01*
X414379Y169317D01*
G03X414753Y169262I374J1247D01*
G03X416055Y170564I0J1302D01*
G03X416000Y170938I-1302J0D01*
G01X415966Y171052D01*
X417914Y173000D01*
X482737D01*
G03X487329I2296J1934D01*
G01X494761D01*
G03X499239I2239J2001D01*
G37*
G36*
G01X626236Y417835D02*
G03X640039Y404032I13803J0D01*
G03X651312Y409871I-1J13803D01*
G02X652039Y409641I327J-230D01*
G01Y291199D01*
G03X647243Y282679I5172J-8522D01*
G01Y241437D01*
G03X652039Y232916I9968J0D01*
G01Y73548D01*
G02X651312Y73318I-400J0D01*
G03X640039Y79156I-11273J-7965D01*
G03X626236Y65354I0J-13803D01*
G03X627899Y58787I13803J1D01*
G02X627547Y58197I-352J-190D01*
G01X585002D01*
Y189763D01*
G03X586002Y192000I-2002J2237D01*
G03X585064Y194180I-3002J0D01*
G01X585002Y194239D01*
Y194843D01*
X585281D01*
X585339Y194789D01*
G03X598999Y189398I13660J14611D01*
G01X599000D01*
G03Y229402I0J20002D01*
G03X581518Y219120I0J-20003D01*
G02X580885Y219031I-350J194D01*
G01X579385Y220532D01*
X579370Y220580D01*
G03X577380Y222570I-2870J-880D01*
G01X577332Y222585D01*
X573122Y226794D01*
X580242Y233914D01*
X580270Y233929D01*
G03X581902Y236600I-1370J2671D01*
G03X581000Y238745I-3001J0D01*
G01Y307672D01*
X590328Y317000D01*
X605000D01*
G03X606414Y317586I0J1999D01*
G01X614914Y326086D01*
G03X615500Y327500I-1413J1414D01*
G01Y383500D01*
G03X614914Y384914I-1999J0D01*
G01X608000Y391828D01*
Y427797D01*
X609801Y429598D01*
X631519D01*
G02X631759Y428878I0J-400D01*
G03X626236Y417835I8280J-11044D01*
G37*
%LPD*%
G75*
G36*
G01X316747Y85237D02*
X314763Y83253D01*
X310516Y87500D01*
X312500Y89484D01*
X316747Y85237D01*
G37*
G36*
G01X387193Y141702D02*
G02Y144308I0J1303D01*
G01X391130D01*
G02Y141702I0J-1303D01*
G01X387193D01*
G37*
G36*
G01X461996Y129890D02*
G02Y132496I0J1303D01*
G01X465933D01*
G02Y129890I0J-1303D01*
G01X461996D01*
G37*
G36*
G01X402942Y149576D02*
G02Y152182I0J1303D01*
G01X406879D01*
G02Y149576I0J-1303D01*
G01X402942D01*
G37*
G36*
G01X395067Y161388D02*
G02Y163992I0J1302D01*
G01X399004D01*
G02Y161388I0J-1302D01*
G01X395067D01*
G37*
G36*
G01Y153514D02*
G02Y156118I0J1302D01*
G01X399004D01*
G02Y153514I0J-1302D01*
G01X395067D01*
G37*
G36*
G01X387193Y165324D02*
G02Y167930I0J1303D01*
G01X391130D01*
G02Y165324I0J-1303D01*
G01X387193D01*
G37*
G36*
G01X402942D02*
G02Y167930I0J1303D01*
G01X406879D01*
G02Y165324I0J-1303D01*
G01X402942D01*
G37*
G36*
G01X387193Y149576D02*
G02Y152182I0J1303D01*
G01X391130D01*
G02Y149576I0J-1303D01*
G01X387193D01*
G37*
G36*
G01Y157450D02*
G02Y160056I0J1303D01*
G01X391130D01*
G02Y157450I0J-1303D01*
G01X387193D01*
G37*
G36*
G01X446248Y187614D02*
G02Y185008I0J-1303D01*
G01X442311D01*
G02Y187614I0J1303D01*
G01X446248D01*
G37*
G36*
G01X600696Y115350D02*
G02X617500Y124503I16804J-10849D01*
G02X637503Y104500I0J-20003D01*
G02X636283Y97621I-20004J0D01*
G02X636500Y96501I-2783J-1120D01*
G01Y96500D01*
G02X634273Y93601I-3000J0D01*
G02X617500Y84497I-16773J10899D01*
G02X597497Y104500I0J20003D01*
G02X598437Y110560I20003J0D01*
G02X597846Y112349I2413J1789D01*
G01Y112350D01*
G02X600696Y115350I3004J0D01*
G37*
G54D42*
X353065Y104707D03*
X455731Y122167D03*
G54D38*
X281801Y198700D03*
G54D43*
X343400Y108500D03*
G54D39*
X284500Y185900D03*
G54D35*
X126067Y184043D03*
X286067Y104043D03*
G54D44*
X365101Y189959D03*
X345301Y191499D03*
G54D33*
X143567Y106043D03*
X146067Y268043D03*
X268567Y255943D03*
Y112143D03*
G54D41*
X295835Y46500D03*
X280087Y36900D03*
X295835D03*
X264339D03*
X619961Y226074D03*
G54D36*
X71900Y357500D03*
X364100Y92000D03*
G54D40*
X494094Y309646D03*
G54D46*
X634055Y367519D03*
Y334449D03*
G54D45*
X473807Y137098D03*
G54D34*
X29528Y373031D03*
G54D37*
X108900Y382500D03*
G54D10*
X8878Y21717D03*
X4878D03*
X4000Y25619D03*
Y29619D03*
Y33619D03*
Y37619D03*
Y41619D03*
Y45619D03*
Y49619D03*
Y281619D03*
Y285619D03*
Y289619D03*
Y293619D03*
Y297619D03*
Y301619D03*
Y305619D03*
Y309619D03*
Y313619D03*
Y337619D03*
Y341619D03*
Y345619D03*
Y349619D03*
Y353619D03*
Y357619D03*
Y361619D03*
Y365619D03*
Y369619D03*
Y373619D03*
Y377619D03*
Y381619D03*
Y385619D03*
Y389619D03*
Y393619D03*
Y397619D03*
Y401619D03*
Y405619D03*
Y409619D03*
Y413619D03*
Y417619D03*
Y421619D03*
Y425619D03*
Y429619D03*
X4413Y433598D03*
X8413D03*
X24878Y21717D03*
X20878D03*
X16878D03*
X12878D03*
X12413Y433598D03*
X16413D03*
X20413D03*
X24413D03*
X28413D03*
X44878Y21717D03*
X40878D03*
X36878D03*
X32878D03*
X28878D03*
X32413Y433598D03*
X36413D03*
X40413D03*
X44413D03*
X55055Y25073D03*
X52878Y21717D03*
X48878D03*
X55055Y41073D03*
Y37073D03*
Y33073D03*
Y29073D03*
X61463Y54048D03*
X57859Y52313D03*
X55558Y49041D03*
X55055Y45073D03*
X48413Y433598D03*
X52413D03*
X56413D03*
X60413D03*
X77460Y54197D03*
X73460D03*
X69460D03*
X65460D03*
X76100Y154400D03*
X75950Y164200D03*
X79248Y266100D03*
X73600Y252500D03*
X67000Y283100D03*
X68600Y274000D03*
X75500Y282500D03*
X63800Y274000D03*
X76700Y357500D03*
X67100D03*
X70500Y419000D03*
X75580Y419004D03*
X68413Y433598D03*
X72413D03*
X76413D03*
X80413D03*
X64413D03*
X97460Y54197D03*
X93460D03*
X89460D03*
X85460D03*
X81460D03*
X86800Y230000D03*
X85600Y263700D03*
X98000Y420000D03*
X90000Y420500D03*
X85500D03*
X84413Y433598D03*
X88413D03*
X92413D03*
X96413D03*
X113460Y54197D03*
X109460D03*
X105460D03*
X101460D03*
X112880Y73020D03*
X113700Y382500D03*
X104100D03*
X104413Y433598D03*
X108413D03*
X112413D03*
X100413D03*
X132920Y51926D03*
X129450Y53917D03*
X125460Y54197D03*
X121460D03*
X117460D03*
X126000Y67000D03*
Y62000D03*
X131500Y290500D03*
X116413Y433598D03*
X120413D03*
X124413D03*
X128413D03*
X132413D03*
X135299Y24509D03*
X150163Y21717D03*
X146163D03*
X142163D03*
X138163D03*
X135299Y28509D03*
Y32509D03*
Y36509D03*
Y40509D03*
Y44509D03*
X134977Y48496D03*
X148500Y62500D03*
X139500D03*
X144000D03*
X138500Y75000D03*
X145900Y75200D03*
X142070Y77900D03*
X142000Y69535D03*
X136000Y290500D03*
X138250Y372250D03*
X138500Y387500D03*
X140413Y433598D03*
X144413D03*
X148413D03*
X136413D03*
X158163Y21717D03*
X154163D03*
X158795Y25667D03*
Y41667D03*
Y37667D03*
Y33667D03*
Y29667D03*
X160736Y49309D03*
X159112Y45654D03*
X163543Y52159D03*
X151840Y79935D03*
X153500Y390500D03*
X163300Y382900D03*
X151100Y386300D03*
X167100Y405600D03*
X152100Y399300D03*
X151530Y406300D03*
X153150Y394590D03*
X160600Y417400D03*
X152200Y416300D03*
X152413Y433598D03*
X156413D03*
X160413D03*
X164413D03*
X183170Y56390D03*
X180341Y47225D03*
X178196Y50601D03*
X180620Y77890D03*
X180390Y70720D03*
X180910Y63390D03*
X168413Y433598D03*
X172413D03*
X176413D03*
X180413D03*
X184413D03*
X191535Y28900D03*
X201950Y29050D03*
X191535Y41200D03*
X198135Y36500D03*
X195000Y54550D03*
X203000Y75000D03*
X196497Y76502D03*
X200413Y433598D03*
X188413D03*
X192413D03*
X196413D03*
X210500Y30500D03*
X207880Y78740D03*
X214810Y78810D03*
X208300Y289500D03*
X217300D03*
X218500Y301700D03*
X213500D03*
X208500D03*
X209660Y331500D03*
X204413Y433598D03*
X208413D03*
X212413D03*
X216413D03*
X220413D03*
X232700Y29100D03*
X221800Y289500D03*
X222000Y330000D03*
X224413Y433598D03*
X228413D03*
X232413D03*
X236413D03*
X254527Y28900D03*
X244619D03*
X254527Y33900D03*
X240508Y76300D03*
Y66700D03*
X243822Y76300D03*
X253422D03*
X240508Y69900D03*
Y73100D03*
X240413Y433598D03*
X244413D03*
X248413D03*
X252413D03*
X264339Y32100D03*
X264304Y28900D03*
X272309D03*
X264339Y41700D03*
X263300Y52200D03*
X263507Y76300D03*
X256413Y433598D03*
X260413D03*
X264413D03*
X268413D03*
X272413D03*
X280087Y41700D03*
Y32100D03*
X280052Y28900D03*
X288057D03*
X288255Y76300D03*
X273107D03*
X278655D03*
X284500Y181100D03*
Y184300D03*
Y187500D03*
X283400Y198700D03*
X280200D03*
X277000D03*
X286600D03*
X284500Y190700D03*
X286151Y329500D03*
X289600Y330100D03*
X288413Y433598D03*
X284413D03*
X280413D03*
X276413D03*
X295835Y41700D03*
Y32100D03*
X295800Y28900D03*
X298726Y43529D03*
Y49471D03*
X307300Y61300D03*
X298700Y327000D03*
Y323500D03*
X293200Y329500D03*
X304413Y433598D03*
X300413D03*
X296413D03*
X292413D03*
X307708Y28900D03*
X321402Y54197D03*
X317402D03*
X310237Y89763D03*
X317025Y82975D03*
X319510Y190299D03*
X322200Y320500D03*
Y325000D03*
X310600Y330500D03*
Y335000D03*
X322200Y338500D03*
X324413Y433598D03*
X320413D03*
X316413D03*
X312413D03*
X308413D03*
X329402Y54197D03*
X325402D03*
X337402D03*
X341402D03*
X333402D03*
X338599Y108500D03*
X341799D03*
X337500Y113000D03*
Y122600D03*
Y116200D03*
Y119400D03*
X329110Y190299D03*
X340413Y433598D03*
X336413D03*
X332413D03*
X328413D03*
X345402Y54197D03*
X349402D03*
X353402D03*
X357402D03*
X349000Y82500D03*
X359300Y92000D03*
X348199Y108500D03*
X348264Y104707D03*
X357864D03*
X344999Y108500D03*
X351464Y104707D03*
X354664D03*
X352300Y175000D03*
X345301Y196299D03*
Y186699D03*
X358400Y182700D03*
X345930Y217000D03*
X354850Y276100D03*
X354800Y285600D03*
Y289800D03*
X355000Y332500D03*
Y328000D03*
X356413Y433598D03*
X352413D03*
X348413D03*
X344413D03*
X369402Y54197D03*
X373402D03*
X377402D03*
X361402D03*
X365402D03*
X373500Y78000D03*
X368900Y92000D03*
X373500Y94000D03*
X365101Y194759D03*
Y185159D03*
X375500Y350500D03*
X376413Y433598D03*
X372413D03*
X368413D03*
X364413D03*
X360413D03*
X381402Y54197D03*
X385402D03*
X389402D03*
X393402D03*
X379500Y72500D03*
X380500Y77400D03*
X381700Y92400D03*
X390000Y100500D03*
X383128Y178372D03*
X383000Y346600D03*
X388500Y391000D03*
X393500D03*
X388500Y400000D03*
X393500D03*
X393000Y418500D03*
X392413Y433598D03*
X388413D03*
X384413D03*
X380413D03*
X397402Y54197D03*
X401402D03*
X405402D03*
X409402D03*
X396400Y100500D03*
X409200D03*
X398450Y116099D03*
X408050D03*
X401650D03*
X404850D03*
X405463Y383000D03*
X410463D03*
X398500Y391000D03*
Y400000D03*
X403000Y418500D03*
X398000D03*
X408413Y433598D03*
X404413D03*
X400413D03*
X396413D03*
X417402Y54197D03*
X421402D03*
X425402D03*
X429402D03*
X413402D03*
X413622Y75000D03*
X415463Y383000D03*
X414000Y419000D03*
X422337Y424000D03*
X416800D03*
X428413Y433598D03*
X424413D03*
X420413D03*
X416413D03*
X412413D03*
X433402Y54197D03*
X437402D03*
X441402D03*
X445402D03*
X444050Y116599D03*
X434450D03*
X437650D03*
X440850D03*
X446500Y289500D03*
X439500Y337892D03*
X442500Y336089D03*
X439500Y341500D03*
X443000Y386500D03*
Y401500D03*
Y396500D03*
X432000D03*
X444000Y416500D03*
X444413Y433598D03*
X440413D03*
X436413D03*
X432413D03*
X449402Y54197D03*
X453402D03*
X457402D03*
X461402D03*
X450930Y122167D03*
X460530D03*
X457330D03*
X454130D03*
X464413Y433598D03*
X460413D03*
X456413D03*
X452413D03*
X448413D03*
X465402Y54197D03*
X469402D03*
X473402D03*
X477402D03*
X481402D03*
X480413Y433598D03*
X476413D03*
X472413D03*
X468413D03*
X485402Y54197D03*
X489402D03*
X493402D03*
X497402D03*
X490970Y133500D03*
Y138500D03*
X488500Y359000D03*
X496413Y433598D03*
X492413D03*
X488413D03*
X484413D03*
X501402Y54197D03*
X505402D03*
X509402D03*
X513402D03*
X500500Y271100D03*
X500000Y278799D03*
X516413Y433598D03*
X512413D03*
X508413D03*
X504413D03*
X500413D03*
X517402Y54197D03*
X521402D03*
X525402D03*
X529402D03*
X533402D03*
X533000Y95000D03*
Y99500D03*
X522400Y270700D03*
X522600Y276200D03*
X528500Y299000D03*
X532300Y425700D03*
X532413Y433598D03*
X528413D03*
X524413D03*
X520413D03*
X537402Y54197D03*
X541402D03*
X545402D03*
X549402D03*
X549500Y69400D03*
X548158Y228033D03*
X545250Y256300D03*
X539977Y275124D03*
X540318Y270436D03*
X537500Y296607D03*
X548413Y433598D03*
X544413D03*
X540413D03*
X536413D03*
X553402Y54197D03*
X557402D03*
X561402D03*
X565402D03*
X568600Y76000D03*
X566600Y212900D03*
X553122Y227979D03*
X559500Y228000D03*
X566700Y227500D03*
X552000Y367597D03*
Y371141D03*
X555200Y367597D03*
Y371141D03*
X552000Y374684D03*
Y378227D03*
X555200D03*
Y374684D03*
X568413Y433598D03*
X564413D03*
X560413D03*
X556413D03*
X552413D03*
X569402Y54197D03*
X573402D03*
X577402D03*
X581402D03*
X585402D03*
X572500Y60301D03*
X572870Y67570D03*
X577100Y227900D03*
X581400Y262100D03*
Y272100D03*
Y282100D03*
X581500Y302100D03*
X576200Y342500D03*
X584413Y433598D03*
X580413D03*
X576413D03*
X572413D03*
X589402Y54197D03*
X593402D03*
X597402D03*
X601402D03*
X597000Y199900D03*
X591902Y200300D03*
X601902Y200100D03*
X594153Y220500D03*
X589953Y236600D03*
X591000Y261500D03*
X590500Y301500D03*
X600413Y433598D03*
X596413D03*
X592413D03*
X588413D03*
X605402Y54197D03*
X609402D03*
X613402D03*
X617402D03*
X621402D03*
X606902Y200400D03*
X619961Y230874D03*
Y221274D03*
X620413Y433598D03*
X616413D03*
X612413D03*
X608413D03*
X604413D03*
X625402Y54197D03*
X629402D03*
X633500Y205906D03*
X625800Y215874D03*
X633000Y267000D03*
X636413Y433598D03*
X632413D03*
X628413D03*
X624413D03*
X649402Y54197D03*
X653402D03*
X656039Y57205D03*
Y61205D03*
Y65205D03*
Y69205D03*
Y73205D03*
Y77205D03*
Y81205D03*
Y85205D03*
Y89205D03*
Y93205D03*
Y97205D03*
Y101205D03*
Y105205D03*
Y109205D03*
Y113205D03*
Y117205D03*
Y121205D03*
Y125205D03*
Y129205D03*
Y145205D03*
Y133205D03*
Y137205D03*
Y141205D03*
Y149205D03*
Y153205D03*
Y157205D03*
Y161205D03*
Y165205D03*
Y169205D03*
Y173205D03*
Y177205D03*
Y181205D03*
Y235585D03*
Y311909D03*
Y315909D03*
Y319909D03*
Y323909D03*
Y327909D03*
Y331909D03*
Y335909D03*
Y339909D03*
Y343909D03*
Y347909D03*
Y351909D03*
Y355909D03*
Y359909D03*
Y363909D03*
Y367909D03*
Y371909D03*
Y375909D03*
Y379909D03*
Y383909D03*
Y387909D03*
Y391909D03*
Y395909D03*
Y399909D03*
Y403909D03*
Y407909D03*
Y411909D03*
Y415909D03*
Y419909D03*
Y423909D03*
Y427909D03*
Y431909D03*
X652413Y433598D03*
X648413D03*
X644413D03*
X640413D03*
G54D13*
X9000Y279000D03*
Y286000D03*
X17500Y91000D03*
X12500D03*
Y101000D03*
Y106000D03*
X19100Y148798D03*
X23600D03*
X28100D03*
X13620Y148720D03*
X13000Y157000D03*
X12500Y162000D03*
X17000Y204500D03*
X12500D03*
Y214500D03*
Y219500D03*
X19000Y262500D03*
X24200Y262508D03*
X28700D03*
X12500Y261500D03*
X19900Y283000D03*
X15000Y279000D03*
X28700Y274300D03*
X13000Y273327D03*
X16000Y302500D03*
X28500Y302000D03*
X28000Y296500D03*
X16000Y307500D03*
X18000Y314500D03*
X13000Y318700D03*
X28000Y327000D03*
X44500Y73500D03*
X45500Y104390D03*
Y126000D03*
X41500Y127500D03*
X41409Y132591D03*
X45500Y161000D03*
X41600Y148798D03*
X32600Y148700D03*
X37100Y148798D03*
X45500Y182500D03*
X45000Y213000D03*
X46000Y219500D03*
X42000Y236800D03*
X40500Y262000D03*
X33200Y262508D03*
X43000Y255500D03*
X29000Y291500D03*
X43000Y314500D03*
X33000D03*
X44500Y309000D03*
X39500D03*
X34500D03*
X35500Y327000D03*
X55500Y59000D03*
X50500Y60228D03*
X51772Y73600D03*
X47600Y68900D03*
X57000Y83500D03*
X51500D03*
X47000Y100000D03*
X61400Y104900D03*
X62500Y100500D03*
X57500Y101500D03*
X48390Y128312D03*
X53740Y126000D03*
X51772Y130500D03*
X55922Y140543D03*
X46500Y133000D03*
X47500Y140500D03*
X53900Y157000D03*
X60600Y161200D03*
X54130Y152500D03*
X60600Y157000D03*
X48957Y153619D03*
X51772Y187987D03*
X53500Y183500D03*
X54000Y213500D03*
X48000Y200500D03*
X53000D03*
X63000Y206000D03*
Y210500D03*
Y215000D03*
X49600Y213455D03*
X57500Y218500D03*
X51772Y245074D03*
X53200Y240187D03*
X48232Y264530D03*
X48500Y252500D03*
X55200Y253500D03*
X48500Y271500D03*
X52500Y278000D03*
X52800Y272000D03*
X57500Y289000D03*
X62000Y307000D03*
X61489Y332329D03*
X62000Y323500D03*
X55000Y336000D03*
Y355400D03*
X63500Y359600D03*
X60300Y407100D03*
Y401100D03*
Y395100D03*
Y413100D03*
X67700Y65000D03*
X66400Y77400D03*
X71500Y77000D03*
X66000Y91100D03*
X76321Y78300D03*
X78500Y82250D03*
X69500Y100000D03*
X73500Y112500D03*
X67000Y109000D03*
X79000Y100500D03*
X74000D03*
X67500Y114500D03*
X68000Y119000D03*
X73500D03*
X69500Y130000D03*
X74000D03*
X75000Y141700D03*
X69000Y187500D03*
Y193000D03*
X69023Y198524D03*
X74593Y202207D03*
X71400Y221700D03*
X67500Y222900D03*
X67400Y227100D03*
X71400Y232900D03*
X71500Y247800D03*
X68000Y235500D03*
X67700Y240200D03*
X72400Y264600D03*
X80148Y253648D03*
X69500Y257800D03*
X64248Y258000D03*
X64500Y296750D03*
X78000Y291500D03*
X66000Y318500D03*
X79000Y315500D03*
X72000Y335000D03*
X66000Y323500D03*
X78635Y324492D03*
X79500Y341790D03*
Y348500D03*
X72000Y346300D03*
X80700Y399200D03*
Y404200D03*
X71300D03*
Y399200D03*
X76000D03*
Y404200D03*
X71300Y394200D03*
X76000D03*
X80700D03*
X64300Y407600D03*
Y401600D03*
Y395600D03*
X66000Y419000D03*
X80500Y420500D03*
X80700Y409200D03*
X76000D03*
X71300D03*
X64300Y413600D03*
X88900Y67000D03*
X84200Y75000D03*
X83300Y87100D03*
X96500Y98000D03*
X92250Y97750D03*
X94500Y105000D03*
X89000Y110500D03*
X93500D03*
X90500Y105000D03*
X84000Y100500D03*
X87000Y130000D03*
Y120000D03*
X93500Y125000D03*
X87000Y125500D03*
X93500Y130000D03*
X86600Y141300D03*
X90500Y144500D03*
X95500Y145500D03*
X96500Y140000D03*
X91500D03*
X93900Y155200D03*
X95200Y151000D03*
X88500Y149000D03*
X94500Y163000D03*
X98500Y159000D03*
X91000Y181500D03*
X88250Y177250D03*
X83500Y178000D03*
X97500Y172000D03*
X98500Y165500D03*
X92000Y173000D03*
X83500D03*
X95500Y192000D03*
X83500Y193000D03*
Y188500D03*
X90500D03*
X94500Y197000D03*
X90500Y193500D03*
X85750Y202750D03*
X97500Y214000D03*
X84500Y218000D03*
X95700Y227500D03*
X98500Y218500D03*
X93032Y246477D03*
X96000Y241000D03*
X85700Y236500D03*
X96500Y235500D03*
X87200Y258300D03*
X98700Y268300D03*
X98500Y256661D03*
X83200Y260300D03*
X86900Y267200D03*
X95900Y278900D03*
X95593Y333347D03*
X82500Y339000D03*
X82951Y327940D03*
X97500Y341000D03*
X95100Y351900D03*
X83000Y352500D03*
Y344500D03*
X91500Y359500D03*
X83500Y360000D03*
X85400Y404200D03*
Y399200D03*
Y394200D03*
X96800Y408100D03*
X92800D03*
Y402100D03*
X96800D03*
Y396100D03*
X92800D03*
X94000Y420000D03*
X83000Y417000D03*
X85400Y409200D03*
X96800Y414100D03*
X92800D03*
X103800Y76240D03*
X99000Y175500D03*
Y188500D03*
Y197500D03*
Y206500D03*
Y201500D03*
Y260025D03*
X98800Y272400D03*
X112500Y302000D03*
X107500D03*
X112500Y290000D03*
X102500D03*
X104500Y305500D03*
X105410Y318500D03*
X99000Y350000D03*
X101500Y341000D03*
X104019Y347425D03*
X103000Y351500D03*
X114000Y352000D03*
X103000Y364000D03*
X106500D03*
X110000D03*
X115500Y389000D03*
X104500Y377000D03*
X102500Y420000D03*
X119500Y57694D03*
X126000Y72000D03*
X127500Y290500D03*
X125095Y306095D03*
X129000Y321500D03*
X126000Y318000D03*
X129500Y328000D03*
X123500Y347500D03*
X130000Y349664D03*
X119000Y352000D03*
X124500D03*
X120000Y364500D03*
X129000Y365000D03*
Y370500D03*
X120000Y368000D03*
Y371500D03*
X132000Y379000D03*
X118500D03*
X132000Y375500D03*
X127000Y397061D03*
X117000Y397000D03*
X121169Y396892D03*
X150860Y67400D03*
X145000Y296500D03*
X141000Y298500D03*
X140100Y306900D03*
X135000Y312000D03*
X142130Y325630D03*
X146000Y334000D03*
X140900Y355400D03*
X142000Y350000D03*
X148000Y370000D03*
X145000Y359000D03*
X140123Y391604D03*
X135500Y383000D03*
Y390500D03*
X141000Y379500D03*
X140100Y395600D03*
X135500Y396000D03*
X135200Y408400D03*
X140000Y401000D03*
X135100Y412600D03*
X143500Y418000D03*
X151200Y75191D03*
X165000Y294000D03*
X166150Y304050D03*
X156800Y301100D03*
X156600Y295000D03*
X156000Y320500D03*
Y316500D03*
X166700Y338800D03*
X151000Y324200D03*
X159100Y350400D03*
X151500Y370000D03*
X159100Y382600D03*
X163600Y378600D03*
X157900Y387400D03*
X158500Y405200D03*
X160582Y410000D03*
X160550Y413400D03*
X151700Y411300D03*
X173170Y70840D03*
X168500Y294000D03*
X169850Y298950D03*
X182600Y289500D03*
X179500Y294600D03*
X176500Y290000D03*
X178000Y309500D03*
X173800Y324100D03*
X178600Y378600D03*
Y374600D03*
X175100Y382600D03*
Y387100D03*
X174600Y401600D03*
Y406100D03*
X175000Y394500D03*
X177000Y398000D03*
X174600Y410600D03*
X176000Y416000D03*
X188900Y54960D03*
X192160Y77840D03*
X190000Y301500D03*
Y305500D03*
X189500Y319000D03*
X189000Y326000D03*
X195900Y332500D03*
X191500Y413000D03*
X213500Y54000D03*
X208160Y73990D03*
X215000Y69000D03*
X220000D03*
X204770Y67780D03*
X207800Y83010D03*
X205000Y348800D03*
Y353800D03*
X215000Y343800D03*
X219000Y348800D03*
X218000Y381100D03*
X219000Y392500D03*
X215500D03*
X216500Y396000D03*
X220000D03*
X217600Y415100D03*
X223500Y58250D03*
X228500Y75500D03*
X226500Y334000D03*
X222500Y324500D03*
X238000Y345000D03*
X225500Y347500D03*
X230000D03*
X228500Y382500D03*
X221500Y378500D03*
X226000D03*
X221500Y415000D03*
X225600Y415100D03*
X229500Y415000D03*
X254000Y213500D03*
X241441Y215000D03*
X241900Y238800D03*
X255400Y290100D03*
X272330Y54871D03*
X259500Y70100D03*
X271000Y184500D03*
X269000Y215000D03*
X259000Y223000D03*
X282200Y179121D03*
X275260Y223000D03*
X280500Y224300D03*
X288000Y293000D03*
X288500Y317000D03*
X303500Y69400D03*
X296400Y70200D03*
X307500Y160500D03*
X303500Y164000D03*
X298284Y175184D03*
X298500Y184500D03*
X300995Y187611D03*
X297772Y188694D03*
X292000Y294720D03*
X299500Y295500D03*
X301000Y312000D03*
X297000Y310500D03*
X301000Y317000D03*
X293700Y317300D03*
X312500Y160500D03*
X320500Y170000D03*
X311000Y193500D03*
X312000Y217000D03*
X308967Y204000D03*
X324000Y227500D03*
X312000Y234400D03*
X324000Y220750D03*
X312500Y225400D03*
X311900Y229900D03*
X311600Y252400D03*
X312000Y269000D03*
Y256500D03*
Y264500D03*
X314500Y276500D03*
X312000Y295500D03*
X310500Y321000D03*
X312500Y307500D03*
X310600Y326000D03*
X321899Y343000D03*
X320000Y398500D03*
X323000Y401500D03*
X321300Y423600D03*
X324800Y415200D03*
X321300Y416700D03*
X324800Y410700D03*
X336000Y61060D03*
X340500Y63500D03*
Y87000D03*
X338000Y102500D03*
X332550Y213550D03*
X341500Y233500D03*
X327923Y221577D03*
X335153Y217875D03*
X340953Y237000D03*
X328500Y258900D03*
X333500D03*
X338500Y259000D03*
X339500Y282000D03*
X330500Y291500D03*
X341000Y304000D03*
X332500Y306500D03*
X328000D03*
X338000Y315000D03*
X341400Y323500D03*
X326000Y374000D03*
X325300Y387200D03*
X331500Y376000D03*
X338500D03*
X342000D03*
X339200Y380300D03*
X339300Y384000D03*
Y387700D03*
X340500Y391600D03*
X325300Y396200D03*
Y391700D03*
X336300Y423200D03*
Y415200D03*
Y419200D03*
X340800Y415200D03*
X349500Y61000D03*
X354500Y60920D03*
X345500Y87000D03*
X354000Y82500D03*
X344000Y103000D03*
X354000Y128000D03*
X351000Y130500D03*
X353500D03*
X356000D03*
X350100Y169400D03*
X352600D03*
X357600D03*
X355100D03*
X347300Y179000D03*
X346500Y174000D03*
X344500Y181500D03*
X351200Y196600D03*
X349128Y186628D03*
X344000Y212000D03*
X350500Y229500D03*
X355500Y218000D03*
Y220500D03*
Y225500D03*
Y223000D03*
X351000Y233243D03*
X355000Y242500D03*
X354975Y247900D03*
X351000Y237000D03*
X343500Y258900D03*
X352500Y260000D03*
X348500D03*
X357680Y271780D03*
X357000Y295500D03*
X356000Y302300D03*
X349000Y303000D03*
Y295500D03*
X355500Y306500D03*
X346000D03*
X351000Y308000D03*
X355000Y337000D03*
X347700Y381600D03*
X347000Y391200D03*
X360000Y402400D03*
X359800Y397700D03*
X347600Y398800D03*
X348279Y405678D03*
X343700Y409900D03*
X348863Y410500D03*
X376838Y100230D03*
X369310Y109500D03*
X369172Y102828D03*
X367000Y126000D03*
X374300Y129000D03*
X371800D03*
X362000Y123500D03*
Y128000D03*
X374300Y132000D03*
X371800D03*
X376500Y141000D03*
X374000D03*
X363600Y176600D03*
X367600Y169300D03*
X364700Y169400D03*
X367400Y174400D03*
X373649Y185735D03*
X369560Y213000D03*
X372060D03*
X367000D03*
X364500D03*
X367000Y232000D03*
X372500D03*
X377500Y218500D03*
Y221000D03*
Y226500D03*
Y223500D03*
X360500Y243000D03*
X367000Y241243D03*
X373500Y247000D03*
X365500Y246500D03*
X369500Y267500D03*
X375800Y255200D03*
X376500Y269000D03*
X365000Y268000D03*
X362300Y286100D03*
X365800D03*
X374800Y291100D03*
X370300D03*
X361500Y296100D03*
X365800Y291100D03*
X362100Y291000D03*
X375500Y309200D03*
X371000Y326000D03*
X370000Y337000D03*
Y332500D03*
X366000Y350850D03*
X360700Y406200D03*
X363100Y418300D03*
X360311Y409880D03*
X363100Y422800D03*
X364500Y413500D03*
X382286Y86214D03*
X384000Y102980D03*
Y109500D03*
X379000Y141000D03*
X382000Y142000D03*
X379800Y177100D03*
X380000Y204500D03*
X384091Y200091D03*
X391900Y246800D03*
X386000D03*
X380100D03*
X378000Y273500D03*
X389400Y281100D03*
X394800Y281300D03*
X388650Y292650D03*
X378000Y293200D03*
X383000D03*
X393300Y312500D03*
X383000Y323500D03*
X390000Y338500D03*
X392500Y329100D03*
Y323900D03*
X383000Y341500D03*
X384300Y368700D03*
X383900Y372600D03*
X381000Y365000D03*
X386500D03*
X389500Y370000D03*
X395000D03*
Y360000D03*
X383900Y384600D03*
X379500Y381000D03*
Y375800D03*
Y417500D03*
X407000Y120000D03*
X399500D03*
X399000Y221407D03*
Y225000D03*
X397800Y246800D03*
X403700D03*
X409300D03*
X397800Y259300D03*
X403700D03*
X400000Y265500D03*
X399800Y278400D03*
X409100Y281300D03*
X409300Y286300D03*
X402000Y303000D03*
X409200Y291700D03*
X396981Y304482D03*
X407500Y300500D03*
X402500Y308000D03*
X397500Y312900D03*
X407500Y305000D03*
X397300Y320700D03*
X408500Y316500D03*
Y321998D03*
Y311000D03*
X398000Y336500D03*
X410000Y338000D03*
X398000Y352000D03*
X406610Y353410D03*
X411840Y353620D03*
X410000Y358543D03*
X409000Y371339D03*
X409650Y403950D03*
X412350Y401250D03*
Y397150D03*
X409650Y394450D03*
X422000Y77500D03*
X417500Y75000D03*
X413500Y88500D03*
X425000Y87700D03*
X423000Y100500D03*
X427800Y100300D03*
X429400Y107500D03*
X420900Y246800D03*
X415000D03*
X413000Y300500D03*
X429442Y310075D03*
X417500Y337000D03*
Y352000D03*
X422500Y354500D03*
X428500Y346000D03*
X413500Y373500D03*
X419000D03*
X420500Y366000D03*
X425000Y381000D03*
X420500D03*
X419150Y394450D03*
X416450Y401250D03*
Y397150D03*
X419150Y403950D03*
X423500Y415500D03*
X434500Y77000D03*
X441400Y78100D03*
X433500Y100500D03*
X444200D03*
X431000Y116500D03*
X444000Y226000D03*
X436500Y233000D03*
X443500Y231500D03*
X444000Y250000D03*
X436500Y237500D03*
X435000Y250500D03*
X443500Y236500D03*
X439500Y266500D03*
X444000Y263000D03*
X447000Y283000D03*
X446000Y294000D03*
X439000Y302000D03*
X434500D03*
X433000Y314320D03*
X435143Y306643D03*
X447000Y321998D03*
X440000Y332500D03*
X434000Y328000D03*
X447200Y347500D03*
X433000Y353500D03*
X433500Y366500D03*
X433382Y360466D03*
X438500Y364500D03*
X446000Y374500D03*
X438400Y382400D03*
X430000Y381000D03*
X431000Y406500D03*
Y416000D03*
Y411500D03*
X460000Y76000D03*
X448430Y89540D03*
X463500Y86500D03*
Y92000D03*
X458500Y86500D03*
X450000Y108200D03*
X454600Y108500D03*
X448500Y100500D03*
X462500Y117000D03*
X462000Y224500D03*
X461000Y234500D03*
X457500Y227500D03*
Y223500D03*
X449000Y232500D03*
Y227500D03*
X461000Y230000D03*
X462000Y250000D03*
X448500Y237500D03*
Y250000D03*
X457500Y237400D03*
X453000Y250000D03*
X457000Y258500D03*
X459500Y262000D03*
X461500Y268409D03*
X460000Y284500D03*
Y289500D03*
X460800Y294200D03*
X461000Y302500D03*
X464500Y298500D03*
X456500Y305500D03*
X454000Y312500D03*
X448500Y311500D03*
X461500Y311000D03*
X451000Y306500D03*
X459500Y322000D03*
X459000Y326000D03*
X450900Y330900D03*
X450500Y368500D03*
X453500Y381500D03*
X454000Y393500D03*
Y397000D03*
X450000Y407000D03*
Y416500D03*
Y411500D03*
X481000Y70700D03*
X478000Y78000D03*
X482000Y83500D03*
X465500Y78500D03*
X475500Y82500D03*
X470500D03*
X479867Y138867D03*
X481500Y182016D03*
X481000Y172500D03*
X479246Y178464D03*
X477500Y170500D03*
X478000Y198000D03*
X481500Y193000D03*
X480288Y203788D03*
X471000Y259200D03*
X477500Y259000D03*
X468500Y264500D03*
Y270000D03*
X471000Y347000D03*
X478500Y346000D03*
X481000Y341000D03*
X471400Y363300D03*
X470500Y391000D03*
X493700Y79161D03*
X496000Y85000D03*
X489400Y126300D03*
X493300Y121500D03*
X496000Y163000D03*
Y167500D03*
Y179258D03*
X484000Y166000D03*
X497000Y175000D03*
X485033Y174934D03*
X498060Y185500D03*
X496500Y192500D03*
X483871Y198241D03*
X496500Y197500D03*
X484000Y185500D03*
X497500Y214000D03*
X496000Y205500D03*
X485000Y202739D03*
X490500Y216750D03*
X492500Y226000D03*
X497500D03*
X492500Y272200D03*
X491800Y277700D03*
X497000Y341000D03*
X495000Y346000D03*
X483501D03*
X488500D03*
X504000Y64500D03*
X508500D03*
X513200Y66000D03*
X503005Y99494D03*
X508000Y105500D03*
Y110500D03*
Y115500D03*
X503860Y124150D03*
X503900Y128690D03*
X503950Y143000D03*
X514500Y144000D03*
X503950Y133500D03*
X501500Y192500D03*
X507000D03*
Y188500D03*
X515500Y201000D03*
X513000Y210500D03*
X511500Y206500D03*
X513500Y215500D03*
X509000D03*
X512100Y249500D03*
X507100Y240700D03*
X512100D03*
Y244700D03*
Y262500D03*
X512300Y254400D03*
X512200Y258700D03*
X512650Y268150D03*
X501000Y263500D03*
X511900Y276200D03*
X508950Y273250D03*
X506100Y280600D03*
X509000Y340500D03*
X504500D03*
X505000Y379500D03*
X504500Y376000D03*
X507500Y394500D03*
X503500D03*
X521500Y60000D03*
X529500Y60500D03*
X526500Y67500D03*
X519500Y75500D03*
X533000Y87000D03*
Y82000D03*
X519500Y81500D03*
X520000Y87000D03*
X524900Y99000D03*
X522500Y114500D03*
X533500Y124500D03*
X534000Y160500D03*
X517000Y212500D03*
X533200Y220000D03*
X529800Y223000D03*
X525400Y247000D03*
X522000D03*
X530350Y257480D03*
X524300Y261700D03*
X523900Y257100D03*
X532500Y272500D03*
X531000Y285500D03*
X526000Y295500D03*
X532900Y318900D03*
X527600D03*
X519000Y307500D03*
X532400Y340600D03*
Y345600D03*
X527100Y340600D03*
Y345600D03*
X532200Y377700D03*
X523700Y384100D03*
X528200Y377700D03*
X523700D03*
X518000Y382500D03*
X527500Y389100D03*
X532100Y399000D03*
X527500Y397100D03*
Y393100D03*
X525176Y411925D03*
X522100Y416500D03*
X551500Y59597D03*
X543957Y60543D03*
X537000Y69000D03*
X549000Y63500D03*
Y78223D03*
X544300Y87100D03*
X549400Y81600D03*
X536500Y84500D03*
Y79000D03*
X534500Y130000D03*
Y136500D03*
X534600Y148300D03*
Y152000D03*
X544000Y159000D03*
X542500Y189500D03*
X538500D03*
X540900Y201500D03*
X543500Y205000D03*
X536900Y201500D03*
X545800Y216500D03*
X541000Y216400D03*
X548300Y222600D03*
X546500Y240500D03*
X549000Y267500D03*
X551700Y256300D03*
X541000Y281500D03*
X539500Y292000D03*
X541346Y303507D03*
X542000Y296450D03*
X537500Y304000D03*
X538600Y318900D03*
X538100Y340600D03*
Y345600D03*
X548557Y387700D03*
X540600Y386300D03*
X538500Y407875D03*
X543000Y396700D03*
X548829Y416329D03*
X548500Y411000D03*
X538558Y413779D03*
X550369Y427558D03*
X538558D03*
X562500Y74600D03*
X560650Y70450D03*
X559941Y62120D03*
X563341Y62102D03*
X564350Y65350D03*
X559000Y85000D03*
X560200Y81500D03*
X559000Y88800D03*
X553000Y108500D03*
X568700Y204300D03*
X564700Y204400D03*
X554600Y202400D03*
X558900Y202500D03*
X566950Y220000D03*
X553800Y240200D03*
X560000Y240000D03*
X565400Y244700D03*
X562000Y254870D03*
X554400Y267500D03*
X561700Y320300D03*
X556700D03*
X562500Y336100D03*
Y326100D03*
X562000Y331600D03*
X563700Y352400D03*
X560000Y342100D03*
X568100Y366400D03*
Y361700D03*
X568326Y371200D03*
X563800Y390700D03*
X564500Y379000D03*
X560200Y386500D03*
X567500D03*
X568600Y376000D03*
Y380700D03*
X567500Y403000D03*
X555000Y402000D03*
X567126Y417500D03*
X555315D03*
X562180Y413779D03*
Y427558D03*
X580500Y65800D03*
X580643Y60900D03*
X585900Y79600D03*
X586500Y107000D03*
Y112500D03*
X576459Y161971D03*
X575072Y165500D03*
X580500Y194500D03*
X583000Y192000D03*
X573200Y204300D03*
X586500Y230000D03*
X571000Y217900D03*
X576500Y219700D03*
X569943Y223300D03*
X578900Y236600D03*
X581500Y267000D03*
X581400Y292250D03*
X583000Y297000D03*
X580300Y356700D03*
X576300Y371200D03*
X580200Y361700D03*
X580100Y366700D03*
X580300Y380700D03*
Y375700D03*
Y385700D03*
X578937Y417500D03*
X572500Y413500D03*
X584000Y421900D03*
X573991Y427558D03*
X599000Y92500D03*
X600850Y112350D03*
X592000Y136000D03*
Y141000D03*
Y146000D03*
Y163000D03*
Y151500D03*
Y157063D03*
Y173000D03*
Y178000D03*
Y168000D03*
X597703Y187000D03*
X587500Y190000D03*
X602500Y183000D03*
X601550Y208450D03*
X596450Y210350D03*
X601953Y218853D03*
X590650Y245680D03*
X604000Y254500D03*
X591000Y271500D03*
Y278500D03*
Y291500D03*
X602500Y404000D03*
X591000D03*
X604000Y398000D03*
X597500Y421900D03*
X602559Y417500D03*
X590748Y418725D03*
X597613Y413779D03*
Y427558D03*
X616500Y194874D03*
X606902Y186000D03*
X614100Y224100D03*
X610500Y227000D03*
X609500Y254500D03*
X614500Y403500D03*
X614370Y417500D03*
X609424Y413779D03*
Y427558D03*
X633500Y108000D03*
Y102000D03*
Y96500D03*
X622000Y136000D03*
Y141500D03*
Y146500D03*
Y162000D03*
Y151600D03*
Y157000D03*
Y181500D03*
Y175500D03*
X622035Y167063D03*
X633500Y196874D03*
X628500Y189500D03*
X636000Y216142D03*
X627500Y205374D03*
X626989Y237989D03*
X633000Y286500D03*
X633500Y301500D03*
X647000Y113500D03*
G54D15*
X19878Y36811D03*
X22704Y29987D03*
Y43635D03*
X19878Y373031D03*
X22704Y366207D03*
Y379855D03*
X29528Y27161D03*
X36352Y29987D03*
X39178Y36811D03*
X36352Y43635D03*
X29528Y46461D03*
Y363381D03*
X36352Y366207D03*
X39178Y373031D03*
X36352Y379855D03*
X29528Y382681D03*
X633215Y58530D03*
Y72178D03*
X630389Y65354D03*
X633215Y424659D03*
X630389Y417835D03*
X633215Y411011D03*
X640039Y55704D03*
X646863Y58530D03*
X649689Y65354D03*
X646863Y72178D03*
X640039Y75004D03*
Y408185D03*
X646863Y411011D03*
X649689Y417835D03*
X646863Y424659D03*
X640039Y427485D03*
G54D19*
X46000Y82000D03*
X51765Y96600D03*
X79500Y234500D03*
X79600Y248900D03*
X77964Y260100D03*
X75800Y274300D03*
X72000Y271400D03*
X82500Y230500D03*
X84600Y248900D03*
X89600D03*
X82500Y273200D03*
X87100Y271300D03*
X85800Y287452D03*
X112800Y66600D03*
X243500Y48650D03*
X252700Y44000D03*
X297700Y335100D03*
X324000Y236000D03*
X318000Y268500D03*
X324300Y254700D03*
X327500Y232000D03*
X332600Y246600D03*
X328500Y238645D03*
X327800Y246800D03*
X334350Y282000D03*
X336500Y295000D03*
X336525Y320500D03*
Y325500D03*
X341500Y338500D03*
Y328500D03*
Y333500D03*
X336525Y330500D03*
X342900Y246800D03*
X344000Y295000D03*
X358250Y340050D03*
X361124Y349876D03*
X387193Y143005D03*
X391130D03*
X387193Y150879D03*
X391130D03*
X387193Y158753D03*
X391130D03*
X387193Y166627D03*
X391130D03*
X391600Y304800D03*
X379300Y305000D03*
X383000Y328500D03*
Y333500D03*
X395067Y146942D03*
X399005D03*
X395067Y154816D03*
X399005D03*
X395067Y162690D03*
X399005D03*
X402942Y150879D03*
X406879D03*
X395067Y170564D03*
X399005D03*
X402942Y166627D03*
X406879D03*
X421360Y359970D03*
X446248Y143005D03*
Y186311D03*
X442311D03*
X441500Y297500D03*
X444000Y406500D03*
X431900Y392200D03*
X431169Y401169D03*
X444000Y411500D03*
X461996Y131193D03*
X450185Y143005D03*
X465933Y131193D03*
X473807Y135130D03*
Y139067D03*
Y146942D03*
X469870D03*
X470462Y369462D03*
X470500Y395000D03*
X493500Y359000D03*
X503000Y354600D03*
X550643Y400900D03*
X568000Y356700D03*
X555569Y388051D03*
G54D16*
X16039Y71260D03*
Y128346D03*
Y185433D03*
Y242520D03*
G54D20*
X63500Y84500D03*
X56500Y113000D03*
X54500Y171000D03*
X62000Y199500D03*
X57500Y226500D03*
X63600Y291500D03*
X75500Y62000D03*
X64400Y70000D03*
X64500Y129500D03*
X64700Y251700D03*
X79500Y308500D03*
X71000Y330500D03*
X78000D03*
X73500Y357500D03*
X70300D03*
X94500Y299000D03*
X88500Y303000D03*
X95000Y291500D03*
X87500Y295500D03*
X97800Y391800D03*
X99500Y370000D03*
X110500Y382500D03*
X107300D03*
X201700Y327900D03*
X229582Y48918D03*
X225000Y396000D03*
X250222Y76300D03*
X247022D03*
X264339Y35300D03*
Y38500D03*
X269907Y76300D03*
X266707D03*
X280087Y35300D03*
Y38500D03*
X285055Y76300D03*
X281855D03*
X295835Y35300D03*
Y38500D03*
Y44900D03*
Y48100D03*
X306500Y169500D03*
X314763Y85237D03*
X312500Y87500D03*
X322710Y190299D03*
X323500Y263000D03*
X324000Y301000D03*
X325910Y190299D03*
X338500Y213500D03*
X330500Y265000D03*
X337500D03*
X332000Y301500D03*
X337000Y344000D03*
X345301Y193099D03*
Y189899D03*
X358000Y261500D03*
X344500Y265000D03*
X370500Y84000D03*
X365700Y92000D03*
X362500D03*
X374600Y178200D03*
X365101Y191559D03*
Y188359D03*
X375000Y210000D03*
X369000Y413500D03*
X374500Y418500D03*
X387193Y135130D03*
X391130Y139067D03*
X387193D03*
Y146942D03*
X391130D03*
Y135130D03*
X387193Y154816D03*
Y162690D03*
X391130D03*
Y154816D03*
X387193Y170564D03*
X391130Y178437D03*
X387193D03*
X391130Y170564D03*
Y182374D03*
X387193Y186311D03*
X380000Y210000D03*
X391130Y205996D03*
Y209933D03*
X387193D03*
X394000Y223500D03*
X383000Y232500D03*
X390000D03*
X387193Y217807D03*
X395000Y382000D03*
X395067Y139067D03*
X399005D03*
Y143005D03*
X402942D03*
Y146942D03*
X406879D03*
X410816D03*
X395067Y143005D03*
Y131193D03*
X406879Y135130D03*
X410816D03*
X406879Y139067D03*
X402942D03*
X410811Y131188D03*
X406874D03*
X399000Y135125D03*
Y131188D03*
X395067Y135130D03*
X410816Y143005D03*
Y139067D03*
X406879Y143005D03*
X395067Y150879D03*
X402942Y154816D03*
X399005Y158753D03*
X410816D03*
X402942Y162690D03*
X410816D03*
Y150879D03*
Y154816D03*
X395067Y158753D03*
X406879D03*
X395067Y166627D03*
X410816D03*
X402942Y170564D03*
X406879D03*
X395067Y178437D03*
X399005D03*
X410816D03*
Y170564D03*
X402942Y178437D03*
X395067Y182374D03*
X399005Y186311D03*
Y190248D03*
X406879Y198122D03*
X399005Y182374D03*
X410816Y186311D03*
X395067Y194185D03*
X406879Y182374D03*
Y186311D03*
Y194185D03*
X395067Y186311D03*
Y190248D03*
X402942Y182374D03*
X399005Y198122D03*
X395067D03*
X410816Y182374D03*
Y190248D03*
Y198122D03*
X402942Y186311D03*
Y194185D03*
X399005D03*
X402942Y198122D03*
X410816Y194185D03*
X406879Y190248D03*
X402942Y209933D03*
X395067Y202059D03*
X402942Y205996D03*
X399005D03*
X406879Y202059D03*
X410816Y209933D03*
Y202059D03*
X399005Y209933D03*
X395067D03*
X406879Y205996D03*
Y209933D03*
X402942Y202059D03*
X395067Y205996D03*
X406879Y213870D03*
X408000Y327000D03*
X420500Y82000D03*
X429000Y123500D03*
X422000D03*
X418500Y117000D03*
X415000Y123500D03*
X414753Y131193D03*
X422627Y146942D03*
X426564Y135130D03*
X418690Y139067D03*
X422627Y135130D03*
X418690D03*
X414753D03*
X422627Y131193D03*
X418690D03*
X426564Y146942D03*
Y143005D03*
Y131193D03*
Y139067D03*
X422627D03*
Y143005D03*
X418690D03*
X414753D03*
Y139067D03*
X418690Y146942D03*
X414753D03*
Y162690D03*
Y154816D03*
X418690Y158753D03*
X422627Y162690D03*
Y154816D03*
X426564Y162690D03*
Y158753D03*
X414753Y150879D03*
X422627D03*
X418690D03*
X426564D03*
X418690Y166627D03*
X414753Y170564D03*
X422627D03*
X418690Y178437D03*
X426564Y166627D03*
Y178437D03*
X414753D03*
X422627Y166627D03*
Y178437D03*
Y190248D03*
X426564Y186311D03*
Y190248D03*
X418690Y198122D03*
X422627Y194185D03*
Y186311D03*
Y182374D03*
X426564D03*
X414753Y190248D03*
X418690D03*
Y186311D03*
X414753D03*
Y182374D03*
Y198122D03*
X426564Y194185D03*
X422627Y198122D03*
X418690Y194185D03*
X414753Y213870D03*
X418690Y202059D03*
Y205996D03*
X414753D03*
Y209933D03*
X418690Y213870D03*
X414753Y202059D03*
X426564D03*
Y205996D03*
Y209933D03*
X422627Y202059D03*
Y205996D03*
X418690Y209933D03*
X425400Y229600D03*
X420500Y229500D03*
X414900Y229800D03*
X426564Y217807D03*
X423000Y235400D03*
X416100D03*
X429000Y274000D03*
X442311Y139067D03*
X434437Y143005D03*
X438374Y131193D03*
X446248Y146942D03*
X442311Y143005D03*
Y146942D03*
X438374Y135130D03*
X434437Y146942D03*
X438374D03*
X446248Y139067D03*
X445939Y135439D03*
X438374Y143005D03*
Y139067D03*
X434437D03*
Y135130D03*
Y131193D03*
X446248Y158753D03*
X442311Y162690D03*
X434437D03*
Y154816D03*
X438374Y162690D03*
Y150879D03*
Y158753D03*
X442311Y154816D03*
X434437Y150879D03*
X442311D03*
X446248D03*
X438374Y166627D03*
X446248D03*
X434437Y170564D03*
X442311D03*
X446248Y178437D03*
X434437Y166627D03*
X438374Y178437D03*
X434437D03*
X446248Y170564D03*
X442311Y178437D03*
X446248Y182374D03*
X442311D03*
X438374Y194185D03*
Y190248D03*
X434437D03*
Y194185D03*
Y182374D03*
X438374Y198122D03*
X442311Y190248D03*
Y194185D03*
X434437Y198122D03*
X446248D03*
X438374Y182374D03*
Y186311D03*
X446248Y194185D03*
X442311Y198122D03*
X434437Y205996D03*
X446248Y209933D03*
X438374D03*
Y205996D03*
Y202059D03*
X442311Y209933D03*
X434437Y202059D03*
Y213870D03*
X442311Y205996D03*
X446248D03*
Y202059D03*
X434437Y209933D03*
X438374Y217807D03*
X434437D03*
X430000Y386500D03*
X454122Y143005D03*
X457844Y131408D03*
X450185Y135130D03*
X461996Y139067D03*
X454122D03*
X458059D03*
X461996Y135130D03*
X454122D03*
X457844Y135345D03*
X449876Y131502D03*
X454122Y131193D03*
X458059Y146942D03*
X461996D03*
X450185D03*
X454122D03*
X458059Y143005D03*
X461996D03*
X450185Y139067D03*
X461996Y162690D03*
X458059Y158753D03*
X450185Y154816D03*
X461996Y158753D03*
X450185Y162690D03*
X454122Y158753D03*
Y162690D03*
X458059Y150879D03*
Y162690D03*
X454122Y150879D03*
X461996D03*
X454122Y154816D03*
X458059D03*
X461996D03*
X450185Y150879D03*
X458059Y178437D03*
Y166627D03*
X450185Y170564D03*
X454123D03*
X454122Y166627D03*
Y178437D03*
X461996Y170564D03*
Y178437D03*
X458060Y170564D03*
X461996Y166627D03*
X450185Y182374D03*
X454122Y186311D03*
X450185Y198122D03*
X458059Y190248D03*
X454122Y182374D03*
X461996Y186311D03*
X458059Y182374D03*
X454122Y194185D03*
X450185D03*
X454122Y190248D03*
X458059Y186311D03*
X454122Y198122D03*
X458059D03*
X461996Y190248D03*
Y198122D03*
Y194185D03*
X450185Y186311D03*
Y190248D03*
X461996Y202059D03*
X458059Y213870D03*
X461996Y209933D03*
Y205996D03*
Y213870D03*
X458059Y202059D03*
Y205996D03*
X454122Y209933D03*
X458059D03*
X450185D03*
Y213870D03*
X454122D03*
X450185Y202059D03*
X454122D03*
X450185Y205996D03*
X454122Y217807D03*
X461996D03*
X458059D03*
X479500Y92500D03*
X466500Y110400D03*
X471200Y115700D03*
X481600Y125800D03*
X476800Y120700D03*
X465933Y146942D03*
X469870Y135130D03*
X473807Y143005D03*
X465933Y139067D03*
X469870D03*
Y131193D03*
X473807D03*
X465933Y135130D03*
Y143005D03*
X469870D03*
X473807Y154816D03*
X465933Y162690D03*
X473807Y150879D03*
X465933Y154816D03*
X469870D03*
X475000Y163000D03*
X465933Y158753D03*
Y150879D03*
X469870D03*
Y178437D03*
X473807Y166627D03*
X465933D03*
Y170564D03*
Y178437D03*
X469870Y166627D03*
Y170564D03*
X473807D03*
Y178437D03*
X465933Y190248D03*
Y194185D03*
Y186311D03*
X469870Y190248D03*
X473807Y182374D03*
X469870D03*
X465933D03*
X469870Y186311D03*
X473807Y190248D03*
X469870Y194185D03*
X465933Y198122D03*
X482000Y212500D03*
X473807Y205996D03*
X469870Y213870D03*
Y209933D03*
X465933Y202059D03*
Y205996D03*
X473807Y213870D03*
X469870Y205996D03*
X473807Y209933D03*
X469870Y217807D03*
X473807D03*
X467000Y355500D03*
X482800Y110300D03*
X483000Y133000D03*
X485000Y154000D03*
X497500Y148500D03*
X491000Y154000D03*
X491500Y148500D03*
X497000Y154000D03*
X483100Y272800D03*
X503000Y155000D03*
X503500Y149000D03*
X534500Y253600D03*
X530000Y406500D03*
X544500Y79500D03*
X541000Y96000D03*
X558000Y161500D03*
X566000Y347000D03*
X560000Y401000D03*
X580000Y104800D03*
X576500Y98000D03*
X576000Y246500D03*
X571800Y396500D03*
X587000Y184000D03*
X595500Y239000D03*
X619961Y224474D03*
Y227674D03*
G54D29*
X640952Y201181D03*
Y220867D03*
G54D18*
X22834Y340080D03*
X26378D03*
X28150Y343150D03*
X24606D03*
X29922Y340080D03*
X33466D03*
X37010D03*
X40554D03*
X44098D03*
X45870Y343150D03*
X42326D03*
X38782D03*
X35238D03*
X31694D03*
G54D11*
X6039Y61260D03*
Y81260D03*
Y118346D03*
Y138346D03*
Y175433D03*
Y195433D03*
Y232520D03*
Y252520D03*
X26039Y61260D03*
Y81260D03*
Y118346D03*
Y138346D03*
Y175433D03*
Y195433D03*
Y232520D03*
Y252520D03*
G54D25*
X588779Y334449D03*
Y350984D03*
Y367519D03*
G54D22*
X126067Y104043D03*
Y184043D03*
Y264043D03*
X253967Y93443D03*
X265967D03*
X277867D03*
X286067Y104043D03*
Y264043D03*
G54D14*
X29528Y36811D03*
Y373031D03*
X640039Y65354D03*
Y417835D03*
G54D23*
X143567Y106043D03*
X146067Y268043D03*
X268567Y112143D03*
Y255943D03*
G54D27*
X634055Y334449D03*
Y367519D03*
G54D28*
X651582Y197244D03*
Y224804D03*
G54D17*
X24807Y335985D03*
Y347245D03*
X43705Y331655D03*
Y351576D03*
G54D24*
X255906Y309646D03*
Y412008D03*
X494094Y309646D03*
Y412008D03*
G54D26*
X605315Y334449D03*
Y350984D03*
Y367519D03*
%LPC*%
G75*
G54D30*
G01X136000Y-65500D02*
Y-158000D01*
X506000D01*
Y-65500D01*
X136000D01*
G01X316000D02*
Y-158000D01*
G54D21*
X88300Y163900D03*
X148500Y376000D03*
X187598Y36900D03*
X189500Y33000D03*
X186000D03*
X187598Y28900D03*
X212800Y289500D03*
X224500Y302000D03*
X380400Y81600D03*
X391130Y186311D03*
X385500Y196154D03*
X399005Y150879D03*
X402942Y158753D03*
X406879Y162690D03*
Y154816D03*
X399005Y166627D03*
X406879Y178437D03*
X402942Y190248D03*
X395067Y213870D03*
X410816Y205996D03*
X399005Y202059D03*
X406879Y217807D03*
X418690Y154816D03*
Y162690D03*
X414753Y158753D03*
X422627D03*
X426564Y154816D03*
X418690Y170564D03*
X414753Y166627D03*
X426564Y170564D03*
X414753Y194185D03*
X426564Y198122D03*
X418690Y182374D03*
X422627Y209933D03*
X434437Y158753D03*
X442311D03*
X438374Y154816D03*
X446248D03*
Y162690D03*
X438374Y170564D03*
X442311Y166627D03*
X446248Y190248D03*
X434437Y186311D03*
X438374Y213870D03*
X442311Y202059D03*
X450185Y158753D03*
Y166627D03*
Y178437D03*
X461996Y182374D03*
X458059Y194185D03*
X454122Y205996D03*
X450185Y217807D03*
X473807Y186311D03*
X469870Y198122D03*
X465933Y209933D03*
G54D12*
X11264Y152264D03*
X12500Y96000D03*
Y209500D03*
X11963Y266437D03*
X16000Y297500D03*
X24100Y310900D03*
X11976Y323524D03*
X37400Y282900D03*
X59600Y60200D03*
X60100Y73000D03*
X50500Y104800D03*
X59000Y96500D03*
X62500Y117000D03*
X60500Y152000D03*
X51400Y161600D03*
X58000Y213500D03*
X51452Y219900D03*
X54590Y266870D03*
X62500Y365000D03*
Y369000D03*
Y373000D03*
Y378000D03*
Y382000D03*
X76400Y87200D03*
X64445Y168945D03*
X73000Y365000D03*
X69500D03*
X66000D03*
X66500Y382000D03*
X70500D03*
X86000Y63100D03*
X82100Y79300D03*
X88400Y154900D03*
X94500Y312500D03*
X95000Y321500D03*
Y344500D03*
X82800Y364600D03*
X94500Y373000D03*
Y369000D03*
Y364500D03*
X90500D03*
X86500D03*
X82800Y384600D03*
X94500Y380500D03*
X94000Y384500D03*
X90500D03*
X86500D03*
X94500Y376500D03*
X111330Y59810D03*
X102500Y302000D03*
X115253Y306247D03*
X113000Y344500D03*
X125000Y76500D03*
X117500Y290000D03*
X149500Y311034D03*
X140700Y320000D03*
X141916Y333916D03*
X137000Y364000D03*
X148500Y380000D03*
X145000Y378000D03*
X153270Y58400D03*
X160500Y75500D03*
Y71500D03*
X153500Y310500D03*
X156000Y325000D03*
Y329000D03*
X159100Y354600D03*
X166700Y343800D03*
X151500Y358000D03*
X219200Y338800D03*
X231000Y68000D03*
Y71500D03*
X228500Y79000D03*
X249000Y290300D03*
X247000Y344500D03*
X251000D03*
X255000D03*
X259500Y54700D03*
X259000Y344500D03*
X309000Y164500D03*
X311900Y243400D03*
X317500Y295500D03*
X321000D03*
X324500D03*
X325000Y363000D03*
X340500Y361300D03*
X332500D03*
X336500D03*
X347500Y141500D03*
X350000D03*
X352500D03*
X355000D03*
X357000Y154200D03*
X353482Y154157D03*
X350085Y154300D03*
X348418Y361300D03*
X344500D03*
X353000Y416500D03*
X350000Y419500D03*
X349500Y415000D03*
X346000Y416000D03*
X360500Y154500D03*
X374900Y154228D03*
X371400Y154300D03*
X367900Y154228D03*
X365500Y279500D03*
X370000Y276000D03*
X374500D03*
X361400Y301500D03*
Y305800D03*
Y309900D03*
X365500Y305900D03*
X378400Y154300D03*
X379500Y237500D03*
X386000Y259250D03*
X378000Y281000D03*
X382200D03*
X407500Y225000D03*
X423000Y72950D03*
X420900Y259000D03*
X424900Y284300D03*
X423900Y278500D03*
X424900Y292900D03*
X439500Y250000D03*
X440000Y278500D03*
X434600Y278300D03*
X435500Y274500D03*
X445600Y278300D03*
X438150Y283800D03*
X433050Y291400D03*
X457500Y250000D03*
X471000Y239000D03*
X477000D03*
X497100Y244700D03*
X497200Y240600D03*
X492300Y240800D03*
X514500Y151000D03*
Y148000D03*
Y154000D03*
Y157000D03*
X502200Y240700D03*
X514000Y374000D03*
X528710Y227500D03*
X534000Y231500D03*
X523600Y281100D03*
X517500Y374000D03*
X543520Y174970D03*
X542270Y169900D03*
X539770Y174900D03*
Y169900D03*
Y172400D03*
X542270D03*
X540600Y234600D03*
X537500Y232000D03*
X539000Y370000D03*
X539300Y365100D03*
X539000Y360000D03*
X543000Y370000D03*
X543300Y365100D03*
X543000Y360000D03*
X565933Y102000D03*
X562533Y102001D03*
X564400Y396700D03*
X585000Y226500D03*
X580300Y390700D03*
X576900Y403100D03*
X588000Y96500D03*
X592000Y127063D03*
X599500Y116500D03*
X594003Y187000D03*
X610500Y190500D03*
X614100Y236400D03*
X618650Y249300D03*
X614500Y398000D03*
X637900Y116900D03*
X622000Y127063D03*
X647000Y108000D03*
G54D31*
G01X329433Y-125500D02*
Y-133000D01*
X333167D01*
G01X340480D02*
Y-128000D01*
G01Y-128875D02*
X340107Y-128375D01*
X339547Y-128125D01*
X338893Y-128000D01*
X338240Y-128250D01*
X337680Y-128750D01*
X337307Y-129500D01*
X337120Y-130500D01*
X337307Y-131500D01*
X337680Y-132250D01*
X338240Y-132750D01*
X338893Y-133000D01*
X339547Y-132875D01*
X340107Y-132500D01*
X340480Y-132000D01*
G01X344340Y-135250D02*
X344900Y-135500D01*
X345647Y-135250D01*
X346113Y-134750D01*
X346487Y-134125D01*
X347047Y-132125D01*
X348260Y-128000D01*
G01X345273D02*
X347047Y-132125D01*
G01X352400Y-129625D02*
X355387D01*
X355107Y-128750D01*
X354640Y-128250D01*
X353987Y-128000D01*
X353333Y-128125D01*
X352773Y-128500D01*
X352400Y-129375D01*
X352213Y-130125D01*
Y-130875D01*
X352400Y-131625D01*
X352867Y-132375D01*
X353427Y-132875D01*
X354080Y-133000D01*
X354733Y-132750D01*
X355387Y-132000D01*
G01X359993Y-133000D02*
Y-128000D01*
G01Y-129000D02*
X360460Y-128500D01*
X360927Y-128125D01*
X361580Y-128000D01*
X362047Y-128125D01*
X362607Y-128500D01*
G01X368800Y-133250D02*
X368613Y-133125D01*
Y-132875D01*
X368800Y-132750D01*
X368987Y-132875D01*
Y-133125D01*
X368800Y-133250D01*
G01Y-129875D02*
X368613Y-129750D01*
Y-129500D01*
X368800Y-129375D01*
X368987Y-129500D01*
Y-129750D01*
X368800Y-129875D01*
G01X336747Y-120500D02*
Y-113000D01*
X338613D01*
X339360Y-113375D01*
X339920Y-113875D01*
X340387Y-114625D01*
X340760Y-115500D01*
X340853Y-116750D01*
X340760Y-118000D01*
X340387Y-118875D01*
X339920Y-119625D01*
X339360Y-120125D01*
X338613Y-120500D01*
X336747D01*
G01X347980D02*
Y-115500D01*
G01Y-116375D02*
X347607Y-115875D01*
X347047Y-115625D01*
X346393Y-115500D01*
X345740Y-115750D01*
X345180Y-116250D01*
X344807Y-117000D01*
X344620Y-118000D01*
X344807Y-119000D01*
X345180Y-119750D01*
X345740Y-120250D01*
X346393Y-120500D01*
X347047Y-120375D01*
X347607Y-120000D01*
X347980Y-119500D01*
G01X353800Y-113000D02*
Y-120500D01*
G01X352493Y-115500D02*
X355107D01*
G01X359900Y-117125D02*
X362887D01*
X362607Y-116250D01*
X362140Y-115750D01*
X361487Y-115500D01*
X360833Y-115625D01*
X360273Y-116000D01*
X359900Y-116875D01*
X359713Y-117625D01*
Y-118375D01*
X359900Y-119125D01*
X360367Y-119875D01*
X360927Y-120375D01*
X361580Y-120500D01*
X362233Y-120250D01*
X362887Y-119500D01*
G01X368800Y-120750D02*
X368613Y-120625D01*
Y-120375D01*
X368800Y-120250D01*
X368987Y-120375D01*
Y-120625D01*
X368800Y-120750D01*
G01Y-117375D02*
X368613Y-117250D01*
Y-117000D01*
X368800Y-116875D01*
X368987Y-117000D01*
Y-117250D01*
X368800Y-117375D01*
G01X382027Y-114250D02*
X382587Y-113500D01*
X383240Y-113125D01*
X383987Y-113000D01*
X384920Y-113250D01*
X385573Y-113875D01*
X385760Y-114625D01*
X385667Y-115375D01*
X385293Y-116000D01*
X383427Y-117250D01*
X382587Y-118125D01*
X382027Y-119375D01*
X381840Y-120500D01*
X385760D01*
G01X391300Y-113000D02*
X390553Y-113250D01*
X389993Y-113875D01*
X389620Y-114625D01*
X389340Y-115625D01*
X389247Y-116750D01*
X389340Y-117875D01*
X389620Y-118875D01*
X389993Y-119625D01*
X390553Y-120250D01*
X391300Y-120500D01*
X392047Y-120250D01*
X392607Y-119625D01*
X392980Y-118875D01*
X393260Y-117875D01*
X393353Y-116750D01*
X393260Y-115625D01*
X392980Y-114625D01*
X392607Y-113875D01*
X392047Y-113250D01*
X391300Y-113000D01*
G01X397027Y-114250D02*
X397587Y-113500D01*
X398240Y-113125D01*
X398987Y-113000D01*
X399920Y-113250D01*
X400573Y-113875D01*
X400760Y-114625D01*
X400667Y-115375D01*
X400293Y-116000D01*
X398427Y-117250D01*
X397587Y-118125D01*
X397027Y-119375D01*
X396840Y-120500D01*
X400760D01*
G01X404527Y-114250D02*
X405087Y-113500D01*
X405740Y-113125D01*
X406487Y-113000D01*
X407420Y-113250D01*
X408073Y-113875D01*
X408260Y-114625D01*
X408167Y-115375D01*
X407793Y-116000D01*
X405927Y-117250D01*
X405087Y-118125D01*
X404527Y-119375D01*
X404340Y-120500D01*
X408260D01*
G01X412587Y-118000D02*
X415013D01*
G01X421300Y-113000D02*
X420553Y-113250D01*
X419993Y-113875D01*
X419620Y-114625D01*
X419340Y-115625D01*
X419247Y-116750D01*
X419340Y-117875D01*
X419620Y-118875D01*
X419993Y-119625D01*
X420553Y-120250D01*
X421300Y-120500D01*
X422047Y-120250D01*
X422607Y-119625D01*
X422980Y-118875D01*
X423260Y-117875D01*
X423353Y-116750D01*
X423260Y-115625D01*
X422980Y-114625D01*
X422607Y-113875D01*
X422047Y-113250D01*
X421300Y-113000D01*
G01X427027Y-114250D02*
X427587Y-113500D01*
X428240Y-113125D01*
X428987Y-113000D01*
X429920Y-113250D01*
X430573Y-113875D01*
X430760Y-114625D01*
X430667Y-115375D01*
X430293Y-116000D01*
X428427Y-117250D01*
X427587Y-118125D01*
X427027Y-119375D01*
X426840Y-120500D01*
X430760D01*
G01X435087Y-118000D02*
X437513D01*
G01X442027Y-114250D02*
X442587Y-113500D01*
X443240Y-113125D01*
X443987Y-113000D01*
X444920Y-113250D01*
X445573Y-113875D01*
X445760Y-114625D01*
X445667Y-115375D01*
X445293Y-116000D01*
X443427Y-117250D01*
X442587Y-118125D01*
X442027Y-119375D01*
X441840Y-120500D01*
X445760D01*
G01X449247Y-119375D02*
X449807Y-120000D01*
X450460Y-120375D01*
X451300Y-120500D01*
X452140Y-120250D01*
X452793Y-119750D01*
X453260Y-118875D01*
X453353Y-117875D01*
X453167Y-116875D01*
X452700Y-116250D01*
X452047Y-115750D01*
X451393Y-115625D01*
X450740Y-115750D01*
X449900Y-116250D01*
X450180Y-113000D01*
X452700D01*
G01X336933Y-108000D02*
Y-100500D01*
X339267D01*
X340013Y-100875D01*
X340480Y-101375D01*
X340667Y-102375D01*
X340480Y-103375D01*
X339920Y-104000D01*
X339267Y-104375D01*
X336933D01*
G01X339267D02*
X340667Y-108000D01*
G01X344900Y-104625D02*
X347887D01*
X347607Y-103750D01*
X347140Y-103250D01*
X346487Y-103000D01*
X345833Y-103125D01*
X345273Y-103500D01*
X344900Y-104375D01*
X344713Y-105125D01*
Y-105875D01*
X344900Y-106625D01*
X345367Y-107375D01*
X345927Y-107875D01*
X346580Y-108000D01*
X347233Y-107750D01*
X347887Y-107000D01*
G01X352120Y-103000D02*
X353800Y-108000D01*
X355480Y-103000D01*
G01X368800Y-108250D02*
X368613Y-108125D01*
Y-107875D01*
X368800Y-107750D01*
X368987Y-107875D01*
Y-108125D01*
X368800Y-108250D01*
G01Y-104875D02*
X368613Y-104750D01*
Y-104500D01*
X368800Y-104375D01*
X368987Y-104500D01*
Y-104750D01*
X368800Y-104875D01*
G01X383800Y-100500D02*
X383053Y-100750D01*
X382493Y-101375D01*
X382120Y-102125D01*
X381840Y-103125D01*
X381747Y-104250D01*
X381840Y-105375D01*
X382120Y-106375D01*
X382493Y-107125D01*
X383053Y-107750D01*
X383800Y-108000D01*
X384547Y-107750D01*
X385107Y-107125D01*
X385480Y-106375D01*
X385760Y-105375D01*
X385853Y-104250D01*
X385760Y-103125D01*
X385480Y-102125D01*
X385107Y-101375D01*
X384547Y-100750D01*
X383800Y-100500D01*
G01X391300Y-108000D02*
Y-100500D01*
X390180Y-102000D01*
G01Y-108000D02*
X392420D01*
G01X336933Y-95500D02*
Y-88000D01*
X339173D01*
X339920Y-88375D01*
X340480Y-89250D01*
X340667Y-90250D01*
X340480Y-91250D01*
X340013Y-92000D01*
X339173Y-92375D01*
X336933D01*
G01X344620Y-95750D02*
X347980Y-88000D01*
G01X351653Y-95500D02*
Y-88000D01*
X355947Y-95500D01*
Y-88000D01*
G01X368800Y-95750D02*
X368613Y-95625D01*
Y-95375D01*
X368800Y-95250D01*
X368987Y-95375D01*
Y-95625D01*
X368800Y-95750D01*
G01Y-92375D02*
X368613Y-92250D01*
Y-92000D01*
X368800Y-91875D01*
X368987Y-92000D01*
Y-92250D01*
X368800Y-92375D01*
G01X381933Y-95500D02*
Y-88000D01*
X384267D01*
X385013Y-88375D01*
X385480Y-88875D01*
X385667Y-89875D01*
X385480Y-90875D01*
X384920Y-91500D01*
X384267Y-91875D01*
X381933D01*
G01X384267D02*
X385667Y-95500D01*
G01X392420D02*
Y-88000D01*
X388967Y-93375D01*
X393633D01*
G01X398800Y-88000D02*
X398053Y-88250D01*
X397493Y-88875D01*
X397120Y-89625D01*
X396840Y-90625D01*
X396747Y-91750D01*
X396840Y-92875D01*
X397120Y-93875D01*
X397493Y-94625D01*
X398053Y-95250D01*
X398800Y-95500D01*
X399547Y-95250D01*
X400107Y-94625D01*
X400480Y-93875D01*
X400760Y-92875D01*
X400853Y-91750D01*
X400760Y-90625D01*
X400480Y-89625D01*
X400107Y-88875D01*
X399547Y-88250D01*
X398800Y-88000D01*
G01X406300D02*
X405553Y-88250D01*
X404993Y-88875D01*
X404620Y-89625D01*
X404340Y-90625D01*
X404247Y-91750D01*
X404340Y-92875D01*
X404620Y-93875D01*
X404993Y-94625D01*
X405553Y-95250D01*
X406300Y-95500D01*
X407047Y-95250D01*
X407607Y-94625D01*
X407980Y-93875D01*
X408260Y-92875D01*
X408353Y-91750D01*
X408260Y-90625D01*
X407980Y-89625D01*
X407607Y-88875D01*
X407047Y-88250D01*
X406300Y-88000D01*
G01X412027Y-92375D02*
X412680Y-91500D01*
X413240Y-91000D01*
X413987Y-90750D01*
X414640Y-91000D01*
X415107Y-91500D01*
X415480Y-92250D01*
X415573Y-93125D01*
X415480Y-93875D01*
X415107Y-94625D01*
X414547Y-95250D01*
X413893Y-95500D01*
X413147Y-95250D01*
X412493Y-94500D01*
X412120Y-93375D01*
X412027Y-92125D01*
X412213Y-90500D01*
X412493Y-89625D01*
X412960Y-88750D01*
X413613Y-88125D01*
X414267Y-88000D01*
X414920Y-88250D01*
X415387Y-88875D01*
G01X420087Y-93000D02*
X422513D01*
G01X429547Y-91500D02*
X429920Y-91125D01*
X430200Y-90500D01*
X430387Y-89625D01*
X430200Y-88875D01*
X429827Y-88375D01*
X429173Y-88000D01*
X426653D01*
Y-95500D01*
X429733D01*
X430387Y-95000D01*
X430760Y-94250D01*
X430947Y-93375D01*
X430760Y-92500D01*
X430200Y-91750D01*
X429547Y-91500D01*
X426653D01*
G01X436300Y-88000D02*
X435553Y-88250D01*
X434993Y-88875D01*
X434620Y-89625D01*
X434340Y-90625D01*
X434247Y-91750D01*
X434340Y-92875D01*
X434620Y-93875D01*
X434993Y-94625D01*
X435553Y-95250D01*
X436300Y-95500D01*
X437047Y-95250D01*
X437607Y-94625D01*
X437980Y-93875D01*
X438260Y-92875D01*
X438353Y-91750D01*
X438260Y-90625D01*
X437980Y-89625D01*
X437607Y-88875D01*
X437047Y-88250D01*
X436300Y-88000D01*
G01X443800D02*
X443053Y-88250D01*
X442493Y-88875D01*
X442120Y-89625D01*
X441840Y-90625D01*
X441747Y-91750D01*
X441840Y-92875D01*
X442120Y-93875D01*
X442493Y-94625D01*
X443053Y-95250D01*
X443800Y-95500D01*
X444547Y-95250D01*
X445107Y-94625D01*
X445480Y-93875D01*
X445760Y-92875D01*
X445853Y-91750D01*
X445760Y-90625D01*
X445480Y-89625D01*
X445107Y-88875D01*
X444547Y-88250D01*
X443800Y-88000D01*
G01X451300D02*
X450553Y-88250D01*
X449993Y-88875D01*
X449620Y-89625D01*
X449340Y-90625D01*
X449247Y-91750D01*
X449340Y-92875D01*
X449620Y-93875D01*
X449993Y-94625D01*
X450553Y-95250D01*
X451300Y-95500D01*
X452047Y-95250D01*
X452607Y-94625D01*
X452980Y-93875D01*
X453260Y-92875D01*
X453353Y-91750D01*
X453260Y-90625D01*
X452980Y-89625D01*
X452607Y-88875D01*
X452047Y-88250D01*
X451300Y-88000D01*
G01X458800Y-95500D02*
Y-88000D01*
X457680Y-89500D01*
G01Y-95500D02*
X459920D01*
G01X465087Y-93000D02*
X467513D01*
G01X473800Y-88000D02*
X473053Y-88250D01*
X472493Y-88875D01*
X472120Y-89625D01*
X471840Y-90625D01*
X471747Y-91750D01*
X471840Y-92875D01*
X472120Y-93875D01*
X472493Y-94625D01*
X473053Y-95250D01*
X473800Y-95500D01*
X474547Y-95250D01*
X475107Y-94625D01*
X475480Y-93875D01*
X475760Y-92875D01*
X475853Y-91750D01*
X475760Y-90625D01*
X475480Y-89625D01*
X475107Y-88875D01*
X474547Y-88250D01*
X473800Y-88000D01*
G01X479527Y-89250D02*
X480087Y-88500D01*
X480740Y-88125D01*
X481487Y-88000D01*
X482420Y-88250D01*
X483073Y-88875D01*
X483260Y-89625D01*
X483167Y-90375D01*
X482793Y-91000D01*
X480927Y-92250D01*
X480087Y-93125D01*
X479527Y-94375D01*
X479340Y-95500D01*
X483260D01*
G54D32*
G01X145964Y-110118D02*
G03I-634J0D01*
G01X149695D02*
G03I-1038J0D01*
G01X168013Y-137456D02*
G03I-634J0D01*
G01X155900Y-133655D02*
G03I-632J0D01*
G01X161735Y-128639D02*
G03I-1458J0D01*
G01X158530Y-131428D02*
G03I-1041J0D01*
G01X158461Y-119126D02*
G03I-1283J0D01*
G01X162690Y-117490D02*
G03I-1584J0D01*
G01X169809Y-121292D02*
G03I-2180J0D01*
G01X165531Y-125255D02*
G03I-1869J0D01*
G01X167813Y-115513D02*
G03I-1971J0D01*
G01X154775Y-120500D02*
G03I-892J0D01*
G01X162681Y-102774D02*
G03I-1584J0D01*
G01X158451Y-101149D02*
G03I-1283J0D01*
G01X159258Y-110118D02*
G03I-1868J0D01*
G01X169812Y-98951D02*
G03I-2180J0D01*
G01X167802Y-104739D02*
G03I-1971J0D01*
G01X165183Y-110118D02*
G03I-2180J0D01*
G01X171881D02*
G03I-2642J0D01*
G01X152135Y-98681D02*
G03I-632J0D01*
G01X154064Y-110118D02*
G03I-1460J0D01*
G01X154764Y-99775D02*
G03I-892J0D01*
G01X158530Y-88809D02*
G03I-1041J0D01*
G01X161742Y-91601D02*
G03I-1458J0D01*
G01X165531Y-94981D02*
G03I-1869J0D01*
G01X171080Y-131739D02*
G03I-1282J0D01*
G01X169322Y-135033D02*
G03I-892J0D01*
G01X180669Y-131528D02*
G03I-1870J0D01*
G01X180255Y-136311D02*
G03I-1456J0D01*
G01X179841Y-140261D02*
G03I-1042J0D01*
G01X179433Y-143587D02*
G03I-634J0D01*
G01X181439Y-119680D02*
G03I-2640J0D01*
G01X175373Y-123081D02*
G03I-1968J0D01*
G01X173018Y-127816D02*
G03I-1584J0D01*
G01X174681Y-116876D02*
G03I-2640J0D01*
G01X180979Y-125917D02*
G03I-2180J0D01*
G01X186177Y-123075D02*
G03I-1971J0D01*
G01X188199Y-116876D02*
G03I-2640J0D01*
G01X175452Y-97124D02*
G03I-1968J0D01*
G01X186225Y-97178D02*
G03I-1971J0D01*
G01X181439Y-100556D02*
G03I-2640J0D01*
G01X174681Y-103361D02*
G03I-2640J0D01*
G01X188199D02*
G03I-2640J0D01*
G01X179841Y-79975D02*
G03I-1042J0D01*
G01X171217Y-88444D02*
G03I-1282J0D01*
G01X173123Y-92378D02*
G03I-1584J0D01*
G01X180255Y-83924D02*
G03I-1456J0D01*
G01X180669Y-88708D02*
G03I-1870J0D01*
G01X180979Y-94320D02*
G03I-2180J0D01*
G01X179433Y-76648D02*
G03I-634J0D01*
G01X191096Y-134658D02*
G03I-892J0D01*
G01X192135Y-136781D02*
G03I-631J0D01*
G01X198775Y-128635D02*
G03I-1458J0D01*
G01X195808Y-125255D02*
G03I-1869J0D01*
G01X200547Y-113952D02*
G03X203345Y-117196I7247J3422D01*
G01X192148Y-121285D02*
G03I-2180J0D01*
G01X187928Y-127802D02*
G03I-1584J0D01*
G01X189667Y-131511D02*
G03I-1283J0D01*
G01X200699Y-105836D02*
G03X200547Y-113953I8974J-4228D01*
G01X208284Y-101612D02*
G03X200698Y-105835I-219J-8531D01*
G01X192148Y-98951D02*
G03I-2180J0D01*
G01X191108Y-82727D02*
G03I-634J0D01*
G01X190184Y-85250D02*
G03I-893J0D01*
G01X195808Y-94981D02*
G03I-1869J0D01*
G01X187839Y-92457D02*
G03I-1584J0D01*
G01X189190Y-88538D02*
G03I-1283J0D01*
G01X214259Y-115661D02*
G03X213314Y-114453I-714J415D01*
G01X202049Y-108260D02*
G03X205722Y-116181I7039J-1548D01*
G01X218075Y-112869D02*
G03X219083Y-115752I4343J-99D01*
G01X208854Y-116658D02*
G03X213313Y-114452I-2485J10632D01*
G01X208470Y-118462D02*
G03X214261Y-115663I-1122J9711D01*
G01X203346Y-117195D02*
G03X208470Y-118461I4545J7394D01*
G01X205721Y-116179D02*
G03X208853Y-116659I2561J6250D01*
G01X215903Y-114020D02*
G03X219079Y-118061I6190J1597D01*
G01X215904Y-114020D02*
Y-111835D01*
G01X227413Y-112869D02*
X218074D01*
G01X214175Y-103951D02*
G03X208283Y-101613I-6403J-7542D01*
G01X213150Y-105147D02*
G03X214175Y-103951I410J686D01*
G01X213152Y-105146D02*
G03X208030Y-103430I-5122J-6786D01*
G01X208029Y-103429D02*
G03X202049Y-108259I-48J-6058D01*
G01X225189Y-111399D02*
G03X218071I-3559J159D01*
G01X218070Y-111418D02*
Y-111399D01*
G01X225188Y-111418D02*
X218070D01*
G01X227412Y-111835D02*
G03X215906I-5753J223D01*
G01X230059Y-117625D02*
Y-102034D01*
G01X230060Y-117626D02*
G03X232080I1010J239D01*
G01X226590Y-116472D02*
G03X225311Y-115210I-817J451D01*
G01X234673Y-114020D02*
G03X237849Y-118061I6190J1597D01*
G01X232081Y-102041D02*
Y-117625D01*
G01X219083Y-115753D02*
G03X225311Y-115211I2844J3371D01*
G01X219079Y-118060D02*
G03X226591Y-116473I2662J5972D01*
G01X227413Y-111835D02*
Y-112869D01*
G01X232080Y-102041D02*
G03X230060Y-102034I-1011J-236D01*
G01X225188Y-111399D02*
Y-111418D01*
G01X234675Y-114020D02*
Y-111835D01*
G01X246181D02*
G03X234675I-5753J223D01*
G01X252849Y-116771D02*
G03X254892Y-115895I-74J2994D01*
G01X236844Y-112869D02*
G03X237852Y-115752I4343J-99D01*
G01X237848Y-118060D02*
G03X245360Y-116473I2662J5972D01*
G01X245358Y-116472D02*
G03X244079Y-115210I-817J451D01*
G01X237852Y-115753D02*
G03X244080Y-115211I2844J3371D01*
G01X249566Y-115529D02*
G03X252307Y-116760I2985J2980D01*
G01Y-116761D02*
G03X252849Y-116772I366J4691D01*
G01X250282Y-118087D02*
G03X254318Y-118340I2605J9244D01*
G01X247897Y-116444D02*
G03X250283Y-118086I3752J2898D01*
G01X249568Y-115529D02*
G03X247898Y-116443I-748J-616D01*
G01X255608Y-108618D02*
G03X253612Y-107689I-3116J-4086D01*
G01X246181Y-111835D02*
Y-112869D01*
G01D02*
X236844D01*
G01X255002Y-114328D02*
G03X252723Y-112986I-3540J-3405D01*
G01X249955Y-112030D02*
G03X252723Y-112985I8208J19302D01*
G01X243957Y-111399D02*
Y-111418D01*
G01X243958Y-111399D02*
G03X236840I-3559J159D01*
G01X236841Y-111418D02*
Y-111399D01*
G01X243957Y-111418D02*
X236841D01*
G01X248537Y-109748D02*
G03X249956Y-112031I2652J66D01*
G01X248537Y-108250D02*
Y-109748D01*
G01X250179Y-106359D02*
G03X248537Y-108249I2747J-4045D01*
G01X256884Y-107368D02*
G03X250178Y-106359I-4153J-4811D01*
G01X253611Y-107689D02*
G03X251080Y-107949I-869J-3992D01*
G01X251081Y-107948D02*
G03X250837Y-110104I805J-1183D01*
G01Y-110106D02*
G03X254306Y-111513I5270J8013D01*
G01X260954Y-116041D02*
Y-107954D01*
G01X254892Y-115895D02*
G03X255001Y-114328I-764J840D01*
G01X269619Y-117484D02*
Y-106797D01*
G01X269620Y-117484D02*
G03X271926I1153J198D01*
G01X266864Y-117375D02*
G03X266002Y-116329I-764J249D01*
G01X262978Y-115462D02*
G03X266002Y-116329I2046J1428D01*
G01X260955Y-116043D02*
G03X264164Y-118351I2956J725D01*
G01X265463Y-118350D02*
X264165D01*
G01X265464Y-118352D02*
G03X266864Y-117374I-24J1525D01*
G01X256906Y-116470D02*
G03X257054Y-113728I-3143J1545D01*
G01X254317Y-118340D02*
G03X256906Y-116470I-1259J4470D01*
G01X262978Y-107954D02*
Y-115463D01*
G01X257054Y-113729D02*
G03X254307Y-111513I-3470J-1490D01*
G01X271969Y-102342D02*
G03I-1194J0D01*
G01X271926Y-106797D02*
G03X269620I-1153J-409D01*
G01X266003Y-107954D02*
X262978D01*
G01X266004Y-107955D02*
G03X266008Y-105932I-177J1012D01*
G01X262978D02*
X266008D01*
G01X262971Y-103419D02*
X262978Y-105932D01*
G01X262972Y-103418D02*
G03X260954Y-103491I-1005J-141D01*
G01Y-105932D02*
Y-103492D01*
G01X259930Y-105932D02*
X260954D01*
G01X259930D02*
G03X259981Y-107955I298J-1005D01*
G01X260954Y-107954D02*
X259982D01*
G01X255606Y-108620D02*
G03X256885Y-107367I599J667D01*
G01X290671Y-110842D02*
G03X290703Y-118351I860J-3751D01*
G01X276837Y-114305D02*
G03X278891Y-116297I4069J2141D01*
G01X274529Y-113568D02*
G03X275888Y-116443I5718J944D01*
G01X275887D02*
G03X279572Y-118352I4392J3967D01*
G01X281425Y-118350D02*
X279571D01*
G01X281425D02*
G03X284525Y-117161I0J4636D01*
G01X285201Y-116508D02*
X284524Y-117161D01*
G01X285201Y-116508D02*
G03X283966Y-115211I-695J574D01*
G01X281510Y-116675D02*
G03X283966Y-115212I-989J4453D01*
G01X278889Y-116297D02*
G03X281508Y-116677I1946J4197D01*
G01X271926Y-106797D02*
Y-117484D01*
G01X274529Y-113566D02*
Y-111839D01*
G01X276446Y-112943D02*
G03X276837Y-114305I4162J458D01*
G01X276445Y-112066D02*
Y-112943D01*
G01X283833Y-109274D02*
G03X285403Y-108106I585J852D01*
G01X285402D02*
G03X280919Y-105777I-4776J-3714D01*
G01X279541D02*
X280919D01*
G01X279540D02*
G03X274999Y-109274I1260J-6333D01*
G01X274998D02*
G03X274529Y-111839I9988J-3152D01*
G01X276849Y-109932D02*
G03X276446Y-112066I5467J-2137D01*
G01X280036Y-107542D02*
G03X276849Y-109933I664J-4205D01*
G01X282662Y-108199D02*
G03X280037Y-107539I-2313J-3650D01*
G01X283833Y-109275D02*
G03X282662Y-108202I-9277J-8949D01*
G01X294457Y-116619D02*
G03Y-112289I-51J2165D01*
G01X291853Y-116620D02*
X294456D01*
G01X291853Y-112289D02*
G03Y-116619I195J-2165D01*
G01X294165Y-118350D02*
X290701D01*
G01X294165D02*
G03X296471Y-117226I-1088J5161D01*
G01X296473Y-117625D02*
Y-117226D01*
G01X296474Y-117627D02*
G03X298494I1010J185D01*
G01X298495Y-109394D02*
Y-117625D01*
G01X301067Y-108534D02*
Y-106508D01*
G01X301615Y-108534D02*
X301067D01*
G01X301615Y-106508D02*
Y-108534D01*
G01X302461Y-106508D02*
X301615D01*
G01X302461Y-106001D02*
Y-106508D01*
G01X300223Y-106001D02*
X302461D01*
G01X300223Y-106508D02*
Y-106001D01*
G01X301067Y-106508D02*
X300223D01*
G01X305164Y-106001D02*
X304731D01*
G01X305713Y-108544D02*
X305164Y-106001D01*
G01X305171Y-108544D02*
X305713D01*
G01X304889Y-106871D02*
X305171Y-108544D01*
G01X304309D02*
X304889Y-106871D01*
G01X304086Y-108544D02*
X304309D01*
G01X303501Y-106887D02*
X304086Y-108544D01*
G01X303226D02*
X303501Y-106887D01*
G01X302698Y-108544D02*
X303226D01*
G01X303243Y-106001D02*
X302698Y-108544D01*
G01X303648Y-106001D02*
X303243D01*
G01X304192Y-107632D02*
X303648Y-106001D01*
G01X304731D02*
X304192Y-107632D01*
G01X294456Y-112288D02*
X291853D01*
G01X296473Y-110841D02*
Y-109686D01*
G01X296472Y-110841D02*
G03X292878Y-110536I-3256J-17043D01*
G01X292879Y-110535D02*
G03X290670Y-110842I280J-10112D01*
G01X298496Y-109394D02*
G03X295031Y-105933I-3962J-501D01*
G01X291563Y-105932D02*
X295031D01*
G01X291562D02*
G03X289112Y-107085I584J-4421D01*
G01Y-107086D02*
G03X289820Y-108520I585J-603D01*
G01X290987Y-107954D02*
G03X289821Y-108520I1446J-4464D01*
G01X294740Y-107954D02*
X290987D01*
G01X296473Y-109686D02*
G03X294742Y-107955I-1598J133D01*
G01X381000Y-125000D02*
Y-133000D01*
X385000D01*
G01X391000Y-125000D02*
X390200Y-125267D01*
X389600Y-125933D01*
X389200Y-126733D01*
X388900Y-127800D01*
X388800Y-129000D01*
X388900Y-130200D01*
X389200Y-131267D01*
X389600Y-132067D01*
X390200Y-132733D01*
X391000Y-133000D01*
X391800Y-132733D01*
X392400Y-132067D01*
X392800Y-131267D01*
X393100Y-130200D01*
X393200Y-129000D01*
X393100Y-127800D01*
X392800Y-126733D01*
X392400Y-125933D01*
X391800Y-125267D01*
X391000Y-125000D01*
G01X396800Y-131800D02*
X397400Y-132467D01*
X398100Y-132867D01*
X399000Y-133000D01*
X399900Y-132733D01*
X400600Y-132200D01*
X401100Y-131267D01*
X401200Y-130200D01*
X401000Y-129133D01*
X400500Y-128467D01*
X399800Y-127933D01*
X399100Y-127800D01*
X398400Y-127933D01*
X397500Y-128467D01*
X397800Y-125000D01*
X400500D01*
G01X404000Y-135667D02*
X410000D01*
G01X412500Y-125000D02*
X415000Y-133000D01*
X417500Y-125000D01*
G01X425200Y-125667D02*
X424600Y-125267D01*
X423900Y-125000D01*
X423100D01*
X422200Y-125400D01*
X421500Y-126067D01*
X421000Y-126867D01*
X420600Y-128200D01*
X420500Y-129400D01*
X420700Y-130600D01*
X421000Y-131400D01*
X421600Y-132200D01*
X422300Y-132733D01*
X423000Y-133000D01*
X423700D01*
X424400Y-132733D01*
X425000Y-132333D01*
X425500Y-131800D01*
G01X433200Y-125667D02*
X432600Y-125267D01*
X431900Y-125000D01*
X431100D01*
X430200Y-125400D01*
X429500Y-126067D01*
X429000Y-126867D01*
X428600Y-128200D01*
X428500Y-129400D01*
X428700Y-130600D01*
X429000Y-131400D01*
X429600Y-132200D01*
X430300Y-132733D01*
X431000Y-133000D01*
X431700D01*
X432400Y-132733D01*
X433000Y-132333D01*
X433500Y-131800D01*
G01X439000Y-133000D02*
Y-125000D01*
X437800Y-126600D01*
G01Y-133000D02*
X440200D01*
M02*
